FILE_TYPE = MACRO_DRAWING;
SET COLOR_WIRE YELLOW;
SET COLOR_PROP ORANGE;
SET COLOR_DOT WHITE;
SET COLOR_ARC YELLOW;
SET COLOR_BODY GREEN;
SET COLOR_NOTE PURPLE;
SET PROP_DISPLAY VALUE;
SET PAGE_NUMBER P165;
FORCEADD OFFPAGE..1
(-2575 1600);
FORCEPROP 2 LAST $XR0 29 
J 0
(-2796 1600);
DISPLAY 0.638298 (-2796 1600);
PAINT MONO (-2796 1600);
FORCEPROP 2 LAST CDS_LIB standard
J 0
(-2575 1600);
DISPLAY INVISIBLE (-2575 1600);
FORCEPROP 1 LAST OFFPAGE TRUE
J 0
(-2250 1475);
DISPLAY 0.872340 (-2250 1475);
DISPLAY INVISIBLE (-2250 1475);
FORCEPROP 1 LAST COMMENT_BODY TRUE
J 0
(-2450 1500);
DISPLAY 0.872340 (-2450 1500);
PAINT GREEN (-2450 1500);
DISPLAY INVISIBLE (-2450 1500);
FORCEPROP 2 LAST PATH I1
J 0
(-2825 1650);
DISPLAY 1.021277 (-2825 1650);
DISPLAY INVISIBLE (-2825 1650);
FORCEADD TAP..1
R 2
(-1375 175);
FORCEPROP 3 LASTPIN (-1325 175) SIG_NAME P5E_CPU0_PE1_TX_DN<0>
J 0
(-1315 185);
DISPLAY 0.659574 (-1315 185);
PAINT MONO (-1315 185);
DISPLAY INVISIBLE (-1315 185);
FORCEPROP 1 LASTPIN (-1325 175) BN 0
J 2
(-1313 183);
DISPLAY 0.680851 (-1313 183);
PAINT GREEN (-1313 183);
FORCEPROP 2 LAST CDS_LIB standard
J 0
(-1375 175);
DISPLAY INVISIBLE (-1375 175);
FORCEPROP 1 LAST BODY_TYPE PLUMBING
J 2
(-1375 225);
DISPLAY 0.872340 (-1375 225);
PAINT GREEN (-1375 225);
DISPLAY INVISIBLE (-1375 225);
FORCEPROP 1 LAST HDL_TAP TRUE
J 2
(-1700 50);
DISPLAY 0.872340 (-1700 50);
DISPLAY INVISIBLE (-1700 50);
FORCEPROP 1 LAST PATH I10
J 2
(-1373 175);
DISPLAY 0.872340 (-1373 175);
PAINT GREEN (-1373 175);
DISPLAY INVISIBLE (-1373 175);
FORCEADD TAP..1
(100 2700);
FORCEPROP 3 LASTPIN (50 2700) SIG_NAME P5E_CPU0_PE1_TX_C_DP<11>
J 0
(60 2710);
DISPLAY 0.659574 (60 2710);
PAINT MONO (60 2710);
DISPLAY INVISIBLE (60 2710);
FORCEPROP 1 LASTPIN (50 2700) BN 11
J 0
(38 2708);
DISPLAY 0.680851 (38 2708);
PAINT GREEN (38 2708);
FORCEPROP 2 LAST CDS_LIB standard
J 0
(100 2700);
DISPLAY INVISIBLE (100 2700);
FORCEPROP 1 LAST BODY_TYPE PLUMBING
J 0
(100 2750);
DISPLAY 0.872340 (100 2750);
PAINT GREEN (100 2750);
DISPLAY INVISIBLE (100 2750);
FORCEPROP 1 LAST HDL_TAP TRUE
J 0
(425 2575);
DISPLAY 0.872340 (425 2575);
DISPLAY INVISIBLE (425 2575);
FORCEPROP 1 LAST PATH I100
J 0
(98 2700);
DISPLAY 0.872340 (98 2700);
PAINT GREEN (98 2700);
DISPLAY INVISIBLE (98 2700);
FORCEADD TAP..1
(100 2900);
FORCEPROP 3 LASTPIN (50 2900) SIG_NAME P5E_CPU0_PE1_TX_C_DP<12>
J 0
(60 2910);
DISPLAY 0.659574 (60 2910);
PAINT MONO (60 2910);
DISPLAY INVISIBLE (60 2910);
FORCEPROP 1 LASTPIN (50 2900) BN 12
J 0
(38 2908);
DISPLAY 0.680851 (38 2908);
PAINT GREEN (38 2908);
FORCEPROP 2 LAST CDS_LIB standard
J 0
(100 2900);
DISPLAY INVISIBLE (100 2900);
FORCEPROP 1 LAST BODY_TYPE PLUMBING
J 0
(100 2950);
DISPLAY 0.872340 (100 2950);
PAINT GREEN (100 2950);
DISPLAY INVISIBLE (100 2950);
FORCEPROP 1 LAST HDL_TAP TRUE
J 0
(425 2775);
DISPLAY 0.872340 (425 2775);
DISPLAY INVISIBLE (425 2775);
FORCEPROP 1 LAST PATH I101
J 0
(98 2900);
DISPLAY 0.872340 (98 2900);
PAINT GREEN (98 2900);
DISPLAY INVISIBLE (98 2900);
FORCEADD TAP..1
(100 3100);
FORCEPROP 3 LASTPIN (50 3100) SIG_NAME P5E_CPU0_PE1_TX_C_DP<13>
J 0
(60 3110);
DISPLAY 0.659574 (60 3110);
PAINT MONO (60 3110);
DISPLAY INVISIBLE (60 3110);
FORCEPROP 1 LASTPIN (50 3100) BN 13
J 0
(38 3108);
DISPLAY 0.680851 (38 3108);
PAINT GREEN (38 3108);
FORCEPROP 2 LAST CDS_LIB standard
J 0
(100 3100);
DISPLAY INVISIBLE (100 3100);
FORCEPROP 1 LAST BODY_TYPE PLUMBING
J 0
(100 3150);
DISPLAY 0.872340 (100 3150);
PAINT GREEN (100 3150);
DISPLAY INVISIBLE (100 3150);
FORCEPROP 1 LAST HDL_TAP TRUE
J 0
(425 2975);
DISPLAY 0.872340 (425 2975);
DISPLAY INVISIBLE (425 2975);
FORCEPROP 1 LAST PATH I102
J 0
(98 3100);
DISPLAY 0.872340 (98 3100);
PAINT GREEN (98 3100);
DISPLAY INVISIBLE (98 3100);
FORCEADD TAP..1
(100 3300);
FORCEPROP 3 LASTPIN (50 3300) SIG_NAME P5E_CPU0_PE1_TX_C_DP<14>
J 0
(60 3310);
DISPLAY 0.659574 (60 3310);
PAINT MONO (60 3310);
DISPLAY INVISIBLE (60 3310);
FORCEPROP 1 LASTPIN (50 3300) BN 14
J 0
(38 3308);
DISPLAY 0.680851 (38 3308);
PAINT GREEN (38 3308);
FORCEPROP 2 LAST CDS_LIB standard
J 0
(100 3300);
DISPLAY INVISIBLE (100 3300);
FORCEPROP 1 LAST BODY_TYPE PLUMBING
J 0
(100 3350);
DISPLAY 0.872340 (100 3350);
PAINT GREEN (100 3350);
DISPLAY INVISIBLE (100 3350);
FORCEPROP 1 LAST HDL_TAP TRUE
J 0
(425 3175);
DISPLAY 0.872340 (425 3175);
DISPLAY INVISIBLE (425 3175);
FORCEPROP 1 LAST PATH I103
J 0
(98 3300);
DISPLAY 0.872340 (98 3300);
PAINT GREEN (98 3300);
DISPLAY INVISIBLE (98 3300);
FORCEADD TAP..1
(100 3500);
FORCEPROP 3 LASTPIN (50 3500) SIG_NAME P5E_CPU0_PE1_TX_C_DP<15>
J 0
(60 3510);
DISPLAY 0.659574 (60 3510);
PAINT MONO (60 3510);
DISPLAY INVISIBLE (60 3510);
FORCEPROP 1 LASTPIN (50 3500) BN 15
J 0
(38 3508);
DISPLAY 0.680851 (38 3508);
PAINT GREEN (38 3508);
FORCEPROP 2 LAST CDS_LIB standard
J 0
(100 3500);
DISPLAY INVISIBLE (100 3500);
FORCEPROP 1 LAST BODY_TYPE PLUMBING
J 0
(100 3550);
DISPLAY 0.872340 (100 3550);
PAINT GREEN (100 3550);
DISPLAY INVISIBLE (100 3550);
FORCEPROP 1 LAST HDL_TAP TRUE
J 0
(425 3375);
DISPLAY 0.872340 (425 3375);
DISPLAY INVISIBLE (425 3375);
FORCEPROP 1 LAST PATH I104
J 0
(98 3500);
DISPLAY 0.872340 (98 3500);
PAINT GREEN (98 3500);
DISPLAY INVISIBLE (98 3500);
FORCEADD OFFPAGE..2
(1100 3525);
FORCEPROP 2 LAST $XR0 153 
J 0
(1289 3525);
DISPLAY 0.638298 (1289 3525);
PAINT MONO (1289 3525);
FORCEPROP 2 LAST CDS_LIB standard
J 0
(1100 3525);
DISPLAY INVISIBLE (1100 3525);
FORCEPROP 1 LAST OFFPAGE TRUE
J 0
(1425 3400);
DISPLAY 0.872340 (1425 3400);
DISPLAY INVISIBLE (1425 3400);
FORCEPROP 1 LAST COMMENT_BODY TRUE
J 0
(1055 3430);
DISPLAY 0.872340 (1055 3430);
PAINT GREEN (1055 3430);
DISPLAY INVISIBLE (1055 3430);
FORCEPROP 2 LAST PATH I105
J 0
(1300 3575);
DISPLAY 1.021277 (1300 3575);
DISPLAY INVISIBLE (1300 3575);
FORCEADD OFFPAGE..2
(1100 3575);
FORCEPROP 2 LAST $XR0 153 
J 0
(1289 3575);
DISPLAY 0.638298 (1289 3575);
PAINT MONO (1289 3575);
FORCEPROP 2 LAST CDS_LIB standard
J 0
(1100 3575);
DISPLAY INVISIBLE (1100 3575);
FORCEPROP 1 LAST OFFPAGE TRUE
J 0
(1425 3450);
DISPLAY 0.872340 (1425 3450);
DISPLAY INVISIBLE (1425 3450);
FORCEPROP 1 LAST COMMENT_BODY TRUE
J 0
(1055 3480);
DISPLAY 0.872340 (1055 3480);
PAINT GREEN (1055 3480);
DISPLAY INVISIBLE (1055 3480);
FORCEPROP 2 LAST PATH I106
J 0
(1300 3625);
DISPLAY 1.021277 (1300 3625);
DISPLAY INVISIBLE (1300 3625);
FORCEADD OFFPAGE..1
(1900 3525);
FORCEPROP 2 LAST $XR0 30 
J 0
(1679 3525);
DISPLAY 0.638298 (1679 3525);
PAINT MONO (1679 3525);
FORCEPROP 2 LAST CDS_LIB standard
J 0
(1900 3525);
DISPLAY INVISIBLE (1900 3525);
FORCEPROP 1 LAST OFFPAGE TRUE
J 0
(2225 3400);
DISPLAY 0.872340 (2225 3400);
DISPLAY INVISIBLE (2225 3400);
FORCEPROP 1 LAST COMMENT_BODY TRUE
J 0
(2025 3425);
DISPLAY 0.872340 (2025 3425);
PAINT GREEN (2025 3425);
DISPLAY INVISIBLE (2025 3425);
FORCEPROP 2 LAST PATH I107
J 0
(1650 3575);
DISPLAY 1.021277 (1650 3575);
DISPLAY INVISIBLE (1650 3575);
FORCEADD OFFPAGE..1
(1900 3575);
FORCEPROP 2 LAST $XR0 30 
J 0
(1679 3575);
DISPLAY 0.638298 (1679 3575);
PAINT MONO (1679 3575);
FORCEPROP 2 LAST CDS_LIB standard
J 0
(1900 3575);
DISPLAY INVISIBLE (1900 3575);
FORCEPROP 1 LAST OFFPAGE TRUE
J 0
(2225 3450);
DISPLAY 0.872340 (2225 3450);
DISPLAY INVISIBLE (2225 3450);
FORCEPROP 1 LAST COMMENT_BODY TRUE
J 0
(2025 3475);
DISPLAY 0.872340 (2025 3475);
PAINT GREEN (2025 3475);
DISPLAY INVISIBLE (2025 3475);
FORCEPROP 2 LAST PATH I108
J 0
(1650 3625);
DISPLAY 1.021277 (1650 3625);
DISPLAY INVISIBLE (1650 3625);
FORCEADD TAP..1
R 2
(2850 125);
FORCEPROP 3 LASTPIN (2900 125) SIG_NAME P5E_CPU0_PE3_TX_DP<0>
J 0
(2910 135);
DISPLAY 0.659574 (2910 135);
PAINT MONO (2910 135);
DISPLAY INVISIBLE (2910 135);
FORCEPROP 1 LASTPIN (2900 125) BN 0
J 2
(2912 133);
DISPLAY 0.680851 (2912 133);
PAINT GREEN (2912 133);
FORCEPROP 2 LAST CDS_LIB standard
J 0
(2850 125);
DISPLAY INVISIBLE (2850 125);
FORCEPROP 1 LAST BODY_TYPE PLUMBING
J 2
(2850 175);
DISPLAY 0.872340 (2850 175);
PAINT GREEN (2850 175);
DISPLAY INVISIBLE (2850 175);
FORCEPROP 1 LAST HDL_TAP TRUE
J 2
(2525 0);
DISPLAY 0.872340 (2525 0);
DISPLAY INVISIBLE (2525 0);
FORCEPROP 1 LAST PATH I109
J 2
(2852 125);
DISPLAY 0.872340 (2852 125);
PAINT GREEN (2852 125);
DISPLAY INVISIBLE (2852 125);
FORCEADD TAP..1
R 2
(-1375 375);
FORCEPROP 3 LASTPIN (-1325 375) SIG_NAME P5E_CPU0_PE1_TX_DN<1>
J 0
(-1315 385);
DISPLAY 0.659574 (-1315 385);
PAINT MONO (-1315 385);
DISPLAY INVISIBLE (-1315 385);
FORCEPROP 1 LASTPIN (-1325 375) BN 1
J 2
(-1313 383);
DISPLAY 0.680851 (-1313 383);
PAINT GREEN (-1313 383);
FORCEPROP 2 LAST CDS_LIB standard
J 0
(-1375 375);
DISPLAY INVISIBLE (-1375 375);
FORCEPROP 1 LAST BODY_TYPE PLUMBING
J 2
(-1375 425);
DISPLAY 0.872340 (-1375 425);
PAINT GREEN (-1375 425);
DISPLAY INVISIBLE (-1375 425);
FORCEPROP 1 LAST HDL_TAP TRUE
J 2
(-1700 250);
DISPLAY 0.872340 (-1700 250);
DISPLAY INVISIBLE (-1700 250);
FORCEPROP 1 LAST PATH I11
J 2
(-1373 375);
DISPLAY 0.872340 (-1373 375);
PAINT GREEN (-1373 375);
DISPLAY INVISIBLE (-1373 375);
FORCEADD TAP..1
R 2
(2850 325);
FORCEPROP 3 LASTPIN (2900 325) SIG_NAME P5E_CPU0_PE3_TX_DP<1>
J 0
(2910 335);
DISPLAY 0.659574 (2910 335);
PAINT MONO (2910 335);
DISPLAY INVISIBLE (2910 335);
FORCEPROP 1 LASTPIN (2900 325) BN 1
J 2
(2912 333);
DISPLAY 0.680851 (2912 333);
PAINT GREEN (2912 333);
FORCEPROP 2 LAST CDS_LIB standard
J 0
(2850 325);
DISPLAY INVISIBLE (2850 325);
FORCEPROP 1 LAST BODY_TYPE PLUMBING
J 2
(2850 375);
DISPLAY 0.872340 (2850 375);
PAINT GREEN (2850 375);
DISPLAY INVISIBLE (2850 375);
FORCEPROP 1 LAST HDL_TAP TRUE
J 2
(2525 200);
DISPLAY 0.872340 (2525 200);
DISPLAY INVISIBLE (2525 200);
FORCEPROP 1 LAST PATH I110
J 2
(2852 325);
DISPLAY 0.872340 (2852 325);
PAINT GREEN (2852 325);
DISPLAY INVISIBLE (2852 325);
FORCEADD TAP..1
R 2
(2850 525);
FORCEPROP 3 LASTPIN (2900 525) SIG_NAME P5E_CPU0_PE3_TX_DP<2>
J 0
(2910 535);
DISPLAY 0.659574 (2910 535);
PAINT MONO (2910 535);
DISPLAY INVISIBLE (2910 535);
FORCEPROP 1 LASTPIN (2900 525) BN 2
J 2
(2912 533);
DISPLAY 0.680851 (2912 533);
PAINT GREEN (2912 533);
FORCEPROP 2 LAST CDS_LIB standard
J 0
(2850 525);
DISPLAY INVISIBLE (2850 525);
FORCEPROP 1 LAST BODY_TYPE PLUMBING
J 2
(2850 575);
DISPLAY 0.872340 (2850 575);
PAINT GREEN (2850 575);
DISPLAY INVISIBLE (2850 575);
FORCEPROP 1 LAST HDL_TAP TRUE
J 2
(2525 400);
DISPLAY 0.872340 (2525 400);
DISPLAY INVISIBLE (2525 400);
FORCEPROP 1 LAST PATH I111
J 2
(2852 525);
DISPLAY 0.872340 (2852 525);
PAINT GREEN (2852 525);
DISPLAY INVISIBLE (2852 525);
FORCEADD TAP..1
R 2
(2850 725);
FORCEPROP 3 LASTPIN (2900 725) SIG_NAME P5E_CPU0_PE3_TX_DP<3>
J 0
(2910 735);
DISPLAY 0.659574 (2910 735);
PAINT MONO (2910 735);
DISPLAY INVISIBLE (2910 735);
FORCEPROP 1 LASTPIN (2900 725) BN 3
J 2
(2912 733);
DISPLAY 0.680851 (2912 733);
PAINT GREEN (2912 733);
FORCEPROP 2 LAST CDS_LIB standard
J 0
(2850 725);
DISPLAY INVISIBLE (2850 725);
FORCEPROP 1 LAST BODY_TYPE PLUMBING
J 2
(2850 775);
DISPLAY 0.872340 (2850 775);
PAINT GREEN (2850 775);
DISPLAY INVISIBLE (2850 775);
FORCEPROP 1 LAST HDL_TAP TRUE
J 2
(2525 600);
DISPLAY 0.872340 (2525 600);
DISPLAY INVISIBLE (2525 600);
FORCEPROP 1 LAST PATH I112
J 2
(2852 725);
DISPLAY 0.872340 (2852 725);
PAINT GREEN (2852 725);
DISPLAY INVISIBLE (2852 725);
FORCEADD TAP..1
R 2
(2850 925);
FORCEPROP 3 LASTPIN (2900 925) SIG_NAME P5E_CPU0_PE3_TX_DP<4>
J 0
(2910 935);
DISPLAY 0.659574 (2910 935);
PAINT MONO (2910 935);
DISPLAY INVISIBLE (2910 935);
FORCEPROP 1 LASTPIN (2900 925) BN 4
J 2
(2912 933);
DISPLAY 0.680851 (2912 933);
PAINT GREEN (2912 933);
FORCEPROP 2 LAST CDS_LIB standard
J 0
(2850 925);
DISPLAY INVISIBLE (2850 925);
FORCEPROP 1 LAST BODY_TYPE PLUMBING
J 2
(2850 975);
DISPLAY 0.872340 (2850 975);
PAINT GREEN (2850 975);
DISPLAY INVISIBLE (2850 975);
FORCEPROP 1 LAST HDL_TAP TRUE
J 2
(2525 800);
DISPLAY 0.872340 (2525 800);
DISPLAY INVISIBLE (2525 800);
FORCEPROP 1 LAST PATH I113
J 2
(2852 925);
DISPLAY 0.872340 (2852 925);
PAINT GREEN (2852 925);
DISPLAY INVISIBLE (2852 925);
FORCEADD TAP..1
R 2
(2850 1325);
FORCEPROP 3 LASTPIN (2900 1325) SIG_NAME P5E_CPU0_PE3_TX_DP<6>
J 0
(2910 1335);
DISPLAY 0.659574 (2910 1335);
PAINT MONO (2910 1335);
DISPLAY INVISIBLE (2910 1335);
FORCEPROP 1 LASTPIN (2900 1325) BN 6
J 2
(2912 1333);
DISPLAY 0.680851 (2912 1333);
PAINT GREEN (2912 1333);
FORCEPROP 2 LAST CDS_LIB standard
J 0
(2850 1325);
DISPLAY INVISIBLE (2850 1325);
FORCEPROP 1 LAST BODY_TYPE PLUMBING
J 2
(2850 1375);
DISPLAY 0.872340 (2850 1375);
PAINT GREEN (2850 1375);
DISPLAY INVISIBLE (2850 1375);
FORCEPROP 1 LAST HDL_TAP TRUE
J 2
(2525 1200);
DISPLAY 0.872340 (2525 1200);
DISPLAY INVISIBLE (2525 1200);
FORCEPROP 1 LAST PATH I114
J 2
(2852 1325);
DISPLAY 0.872340 (2852 1325);
PAINT GREEN (2852 1325);
DISPLAY INVISIBLE (2852 1325);
FORCEADD TAP..1
R 2
(2850 1525);
FORCEPROP 3 LASTPIN (2900 1525) SIG_NAME P5E_CPU0_PE3_TX_DP<7>
J 0
(2910 1535);
DISPLAY 0.659574 (2910 1535);
PAINT MONO (2910 1535);
DISPLAY INVISIBLE (2910 1535);
FORCEPROP 1 LASTPIN (2900 1525) BN 7
J 2
(2912 1533);
DISPLAY 0.680851 (2912 1533);
PAINT GREEN (2912 1533);
FORCEPROP 2 LAST CDS_LIB standard
J 0
(2850 1525);
DISPLAY INVISIBLE (2850 1525);
FORCEPROP 1 LAST BODY_TYPE PLUMBING
J 2
(2850 1575);
DISPLAY 0.872340 (2850 1575);
PAINT GREEN (2850 1575);
DISPLAY INVISIBLE (2850 1575);
FORCEPROP 1 LAST HDL_TAP TRUE
J 2
(2525 1400);
DISPLAY 0.872340 (2525 1400);
DISPLAY INVISIBLE (2525 1400);
FORCEPROP 1 LAST PATH I115
J 2
(2852 1525);
DISPLAY 0.872340 (2852 1525);
PAINT GREEN (2852 1525);
DISPLAY INVISIBLE (2852 1525);
FORCEADD TAP..1
R 2
(3100 175);
FORCEPROP 3 LASTPIN (3150 175) SIG_NAME P5E_CPU0_PE3_TX_DN<0>
J 0
(3160 185);
DISPLAY 0.659574 (3160 185);
PAINT MONO (3160 185);
DISPLAY INVISIBLE (3160 185);
FORCEPROP 1 LASTPIN (3150 175) BN 0
J 2
(3162 183);
DISPLAY 0.680851 (3162 183);
PAINT GREEN (3162 183);
FORCEPROP 2 LAST CDS_LIB standard
J 0
(3100 175);
DISPLAY INVISIBLE (3100 175);
FORCEPROP 1 LAST BODY_TYPE PLUMBING
J 2
(3100 225);
DISPLAY 0.872340 (3100 225);
PAINT GREEN (3100 225);
DISPLAY INVISIBLE (3100 225);
FORCEPROP 1 LAST HDL_TAP TRUE
J 2
(2775 50);
DISPLAY 0.872340 (2775 50);
DISPLAY INVISIBLE (2775 50);
FORCEPROP 1 LAST PATH I116
J 2
(3102 175);
DISPLAY 0.872340 (3102 175);
PAINT GREEN (3102 175);
DISPLAY INVISIBLE (3102 175);
FORCEADD TAP..1
R 2
(3100 375);
FORCEPROP 3 LASTPIN (3150 375) SIG_NAME P5E_CPU0_PE3_TX_DN<1>
J 0
(3160 385);
DISPLAY 0.659574 (3160 385);
PAINT MONO (3160 385);
DISPLAY INVISIBLE (3160 385);
FORCEPROP 1 LASTPIN (3150 375) BN 1
J 2
(3162 383);
DISPLAY 0.680851 (3162 383);
PAINT GREEN (3162 383);
FORCEPROP 2 LAST CDS_LIB standard
J 0
(3100 375);
DISPLAY INVISIBLE (3100 375);
FORCEPROP 1 LAST BODY_TYPE PLUMBING
J 2
(3100 425);
DISPLAY 0.872340 (3100 425);
PAINT GREEN (3100 425);
DISPLAY INVISIBLE (3100 425);
FORCEPROP 1 LAST HDL_TAP TRUE
J 2
(2775 250);
DISPLAY 0.872340 (2775 250);
DISPLAY INVISIBLE (2775 250);
FORCEPROP 1 LAST PATH I117
J 2
(3102 375);
DISPLAY 0.872340 (3102 375);
PAINT GREEN (3102 375);
DISPLAY INVISIBLE (3102 375);
FORCEADD TAP..1
R 2
(3100 575);
FORCEPROP 3 LASTPIN (3150 575) SIG_NAME P5E_CPU0_PE3_TX_DN<2>
J 0
(3160 585);
DISPLAY 0.659574 (3160 585);
PAINT MONO (3160 585);
DISPLAY INVISIBLE (3160 585);
FORCEPROP 1 LASTPIN (3150 575) BN 2
J 2
(3162 583);
DISPLAY 0.680851 (3162 583);
PAINT GREEN (3162 583);
FORCEPROP 2 LAST CDS_LIB standard
J 0
(3100 575);
DISPLAY INVISIBLE (3100 575);
FORCEPROP 1 LAST BODY_TYPE PLUMBING
J 2
(3100 625);
DISPLAY 0.872340 (3100 625);
PAINT GREEN (3100 625);
DISPLAY INVISIBLE (3100 625);
FORCEPROP 1 LAST HDL_TAP TRUE
J 2
(2775 450);
DISPLAY 0.872340 (2775 450);
DISPLAY INVISIBLE (2775 450);
FORCEPROP 1 LAST PATH I118
J 2
(3102 575);
DISPLAY 0.872340 (3102 575);
PAINT GREEN (3102 575);
DISPLAY INVISIBLE (3102 575);
FORCEADD TAP..1
R 2
(3100 775);
FORCEPROP 3 LASTPIN (3150 775) SIG_NAME P5E_CPU0_PE3_TX_DN<3>
J 0
(3160 785);
DISPLAY 0.659574 (3160 785);
PAINT MONO (3160 785);
DISPLAY INVISIBLE (3160 785);
FORCEPROP 1 LASTPIN (3150 775) BN 3
J 2
(3162 783);
DISPLAY 0.680851 (3162 783);
PAINT GREEN (3162 783);
FORCEPROP 2 LAST CDS_LIB standard
J 0
(3100 775);
DISPLAY INVISIBLE (3100 775);
FORCEPROP 1 LAST BODY_TYPE PLUMBING
J 2
(3100 825);
DISPLAY 0.872340 (3100 825);
PAINT GREEN (3100 825);
DISPLAY INVISIBLE (3100 825);
FORCEPROP 1 LAST HDL_TAP TRUE
J 2
(2775 650);
DISPLAY 0.872340 (2775 650);
DISPLAY INVISIBLE (2775 650);
FORCEPROP 1 LAST PATH I119
J 2
(3102 775);
DISPLAY 0.872340 (3102 775);
PAINT GREEN (3102 775);
DISPLAY INVISIBLE (3102 775);
FORCEADD TAP..1
R 2
(-1375 575);
FORCEPROP 3 LASTPIN (-1325 575) SIG_NAME P5E_CPU0_PE1_TX_DN<2>
J 0
(-1315 585);
DISPLAY 0.659574 (-1315 585);
PAINT MONO (-1315 585);
DISPLAY INVISIBLE (-1315 585);
FORCEPROP 1 LASTPIN (-1325 575) BN 2
J 2
(-1313 583);
DISPLAY 0.680851 (-1313 583);
PAINT GREEN (-1313 583);
FORCEPROP 2 LAST CDS_LIB standard
J 0
(-1375 575);
DISPLAY INVISIBLE (-1375 575);
FORCEPROP 1 LAST BODY_TYPE PLUMBING
J 2
(-1375 625);
DISPLAY 0.872340 (-1375 625);
PAINT GREEN (-1375 625);
DISPLAY INVISIBLE (-1375 625);
FORCEPROP 1 LAST HDL_TAP TRUE
J 2
(-1700 450);
DISPLAY 0.872340 (-1700 450);
DISPLAY INVISIBLE (-1700 450);
FORCEPROP 1 LAST PATH I12
J 2
(-1373 575);
DISPLAY 0.872340 (-1373 575);
PAINT GREEN (-1373 575);
DISPLAY INVISIBLE (-1373 575);
FORCEADD Q_CAP_DIFFBUS..2
R 2
(3825 125);
FORCEPROP 1 LAST PART_NUMBER SP_CH4221MEE01
J 2
(3709 213);
DISPLAY 0.574468 (3709 213);
PAINT GREEN (3709 213);
DISPLAY INVISIBLE (3709 213);
FORCEPROP 2 LAST VALUE DIFF BUS_0.22UF
J 2
(3675 125);
DISPLAY 0.553191 (3675 125);
FORCEPROP 1 LAST $LOCATION C901
J 2
(4059 142);
DISPLAY 0.723404 (4059 142);
PAINT GREEN (4059 142);
FORCEPROP 2 LASTPIN (3900 125) $PN 1
J 0
(3910 135);
DISPLAY 0.808511 (3910 135);
FORCEPROP 2 LASTPIN (3750 125) $PN 2
J 2
(3740 135);
DISPLAY 0.808511 (3740 135);
FORCEPROP 1 LAST PIN_NAMES_ROTATE TRUE
J 2
(3825 125);
DISPLAY 0.489362 (3825 125);
PAINT GREEN (3825 125);
DISPLAY INVISIBLE (3825 125);
FORCEPROP 2 LAST CDS_LIB pure_quanta
J 2
(3825 125);
DISPLAY INVISIBLE (3825 125);
FORCEPROP 1 LAST CDS_LMAN_SYM_OUTLINE -25,50,25,-50
J 2
(3825 125);
DISPLAY 0.468085 (3825 125);
PAINT GREEN (3825 125);
DISPLAY INVISIBLE (3825 125);
FORCEPROP 2 LAST VOLTAGE 6.3V
J 2
(3475 175);
DISPLAY 0.553191 (3475 175);
DISPLAY INVISIBLE (3475 175);
FORCEPROP 1 LAST MATERIAL X6S
J 2
(3834 204);
DISPLAY 0.574468 (3834 204);
PAINT GREEN (3834 204);
DISPLAY INVISIBLE (3834 204);
FORCEPROP 2 LAST PACK_TYPE C0201
J 2
(3650 175);
DISPLAY 0.553191 (3650 175);
DISPLAY INVISIBLE (3650 175);
FORCEPROP 2 LAST TOLERANCE 20%
J 2
(3750 175);
DISPLAY 0.553191 (3750 175);
DISPLAY INVISIBLE (3750 175);
FORCEPROP 1 LAST PATH I120
J 2
(3825 125);
DISPLAY 0.723404 (3825 125);
DISPLAY INVISIBLE (3825 125);
FORCEPROP 1 LAST $LOCATION C901
J 0
(4075 200);
DISPLAY 1.021277 (4075 200);
DISPLAY INVISIBLE (4075 200);
FORCEPROP 2 LAST CDS_LOCATION C901
J 0
(4075 200);
DISPLAY 1.021277 (4075 200);
DISPLAY INVISIBLE (4075 200);
FORCEPROP 2 LAST $SEC 1
J 2
(4000 200);
DISPLAY 0.680851 (4000 200);
PAINT MONO (4000 200);
DISPLAY INVISIBLE (4000 200);
FORCEPROP 2 LAST CDS_SEC 1
J 2
(4000 200);
DISPLAY 0.680851 (4000 200);
DISPLAY INVISIBLE (4000 200);
FORCEADD Q_CAP_DIFFBUS..2
R 2
(3825 175);
FORCEPROP 1 LAST PART_NUMBER SP_CH4221MEE01
J 2
(3709 263);
DISPLAY 0.574468 (3709 263);
PAINT GREEN (3709 263);
DISPLAY INVISIBLE (3709 263);
FORCEPROP 2 LAST VALUE DIFF BUS_0.22UF
J 2
(3675 175);
DISPLAY 0.553191 (3675 175);
FORCEPROP 1 LAST $LOCATION C900
J 2
(4059 192);
DISPLAY 0.723404 (4059 192);
PAINT GREEN (4059 192);
FORCEPROP 2 LASTPIN (3900 175) $PN 1
J 0
(3910 185);
DISPLAY 0.808511 (3910 185);
FORCEPROP 2 LASTPIN (3750 175) $PN 2
J 2
(3740 185);
DISPLAY 0.808511 (3740 185);
FORCEPROP 1 LAST PIN_NAMES_ROTATE TRUE
J 2
(3825 175);
DISPLAY 0.489362 (3825 175);
PAINT GREEN (3825 175);
DISPLAY INVISIBLE (3825 175);
FORCEPROP 2 LAST CDS_LIB pure_quanta
J 2
(3825 175);
DISPLAY INVISIBLE (3825 175);
FORCEPROP 1 LAST CDS_LMAN_SYM_OUTLINE -25,50,25,-50
J 2
(3825 175);
DISPLAY 0.468085 (3825 175);
PAINT GREEN (3825 175);
DISPLAY INVISIBLE (3825 175);
FORCEPROP 2 LAST VOLTAGE 6.3V
J 2
(3475 225);
DISPLAY 0.553191 (3475 225);
DISPLAY INVISIBLE (3475 225);
FORCEPROP 1 LAST MATERIAL X6S
J 2
(3834 254);
DISPLAY 0.574468 (3834 254);
PAINT GREEN (3834 254);
DISPLAY INVISIBLE (3834 254);
FORCEPROP 2 LAST PACK_TYPE C0201
J 2
(3650 225);
DISPLAY 0.553191 (3650 225);
DISPLAY INVISIBLE (3650 225);
FORCEPROP 2 LAST TOLERANCE 20%
J 2
(3750 225);
DISPLAY 0.553191 (3750 225);
DISPLAY INVISIBLE (3750 225);
FORCEPROP 1 LAST PATH I121
J 2
(3825 175);
DISPLAY 0.723404 (3825 175);
DISPLAY INVISIBLE (3825 175);
FORCEPROP 1 LAST $LOCATION C900
J 0
(4075 250);
DISPLAY 1.021277 (4075 250);
DISPLAY INVISIBLE (4075 250);
FORCEPROP 2 LAST CDS_LOCATION C900
J 0
(4075 250);
DISPLAY 1.021277 (4075 250);
DISPLAY INVISIBLE (4075 250);
FORCEPROP 2 LAST $SEC 1
J 2
(4000 250);
DISPLAY 0.680851 (4000 250);
PAINT MONO (4000 250);
DISPLAY INVISIBLE (4000 250);
FORCEPROP 2 LAST CDS_SEC 1
J 2
(4000 250);
DISPLAY 0.680851 (4000 250);
DISPLAY INVISIBLE (4000 250);
FORCEADD Q_CAP_DIFFBUS..2
R 2
(3825 325);
FORCEPROP 1 LAST PART_NUMBER SP_CH4221MEE01
J 2
(3709 413);
DISPLAY 0.574468 (3709 413);
PAINT GREEN (3709 413);
DISPLAY INVISIBLE (3709 413);
FORCEPROP 2 LAST VALUE DIFF BUS_0.22UF
J 2
(3675 325);
DISPLAY 0.553191 (3675 325);
FORCEPROP 1 LAST $LOCATION C899
J 2
(4059 342);
DISPLAY 0.723404 (4059 342);
PAINT GREEN (4059 342);
FORCEPROP 2 LASTPIN (3900 325) $PN 1
J 0
(3910 335);
DISPLAY 0.808511 (3910 335);
FORCEPROP 2 LASTPIN (3750 325) $PN 2
J 2
(3740 335);
DISPLAY 0.808511 (3740 335);
FORCEPROP 1 LAST PIN_NAMES_ROTATE TRUE
J 2
(3825 325);
DISPLAY 0.489362 (3825 325);
PAINT GREEN (3825 325);
DISPLAY INVISIBLE (3825 325);
FORCEPROP 2 LAST CDS_LIB pure_quanta
J 2
(3825 325);
DISPLAY INVISIBLE (3825 325);
FORCEPROP 1 LAST CDS_LMAN_SYM_OUTLINE -25,50,25,-50
J 2
(3825 325);
DISPLAY 0.468085 (3825 325);
PAINT GREEN (3825 325);
DISPLAY INVISIBLE (3825 325);
FORCEPROP 2 LAST VOLTAGE 6.3V
J 2
(3475 375);
DISPLAY 0.553191 (3475 375);
DISPLAY INVISIBLE (3475 375);
FORCEPROP 1 LAST MATERIAL X6S
J 2
(3834 404);
DISPLAY 0.574468 (3834 404);
PAINT GREEN (3834 404);
DISPLAY INVISIBLE (3834 404);
FORCEPROP 2 LAST PACK_TYPE C0201
J 2
(3650 375);
DISPLAY 0.553191 (3650 375);
DISPLAY INVISIBLE (3650 375);
FORCEPROP 2 LAST TOLERANCE 20%
J 2
(3750 375);
DISPLAY 0.553191 (3750 375);
DISPLAY INVISIBLE (3750 375);
FORCEPROP 1 LAST PATH I122
J 2
(3825 325);
DISPLAY 0.723404 (3825 325);
DISPLAY INVISIBLE (3825 325);
FORCEPROP 1 LAST $LOCATION C899
J 0
(4075 400);
DISPLAY 1.021277 (4075 400);
DISPLAY INVISIBLE (4075 400);
FORCEPROP 2 LAST CDS_LOCATION C899
J 0
(4075 400);
DISPLAY 1.021277 (4075 400);
DISPLAY INVISIBLE (4075 400);
FORCEPROP 2 LAST $SEC 1
J 2
(4000 400);
DISPLAY 0.680851 (4000 400);
PAINT MONO (4000 400);
DISPLAY INVISIBLE (4000 400);
FORCEPROP 2 LAST CDS_SEC 1
J 2
(4000 400);
DISPLAY 0.680851 (4000 400);
DISPLAY INVISIBLE (4000 400);
FORCEADD Q_CAP_DIFFBUS..2
R 2
(3825 525);
FORCEPROP 1 LAST PART_NUMBER SP_CH4221MEE01
J 2
(3709 613);
DISPLAY 0.574468 (3709 613);
PAINT GREEN (3709 613);
DISPLAY INVISIBLE (3709 613);
FORCEPROP 2 LAST VALUE DIFF BUS_0.22UF
J 2
(3675 525);
DISPLAY 0.553191 (3675 525);
FORCEPROP 1 LAST $LOCATION C897
J 2
(4059 542);
DISPLAY 0.723404 (4059 542);
PAINT GREEN (4059 542);
FORCEPROP 2 LASTPIN (3900 525) $PN 1
J 0
(3910 535);
DISPLAY 0.808511 (3910 535);
FORCEPROP 2 LASTPIN (3750 525) $PN 2
J 2
(3740 535);
DISPLAY 0.808511 (3740 535);
FORCEPROP 1 LAST PIN_NAMES_ROTATE TRUE
J 2
(3825 525);
DISPLAY 0.489362 (3825 525);
PAINT GREEN (3825 525);
DISPLAY INVISIBLE (3825 525);
FORCEPROP 2 LAST CDS_LIB pure_quanta
J 2
(3825 525);
DISPLAY INVISIBLE (3825 525);
FORCEPROP 1 LAST CDS_LMAN_SYM_OUTLINE -25,50,25,-50
J 2
(3825 525);
DISPLAY 0.468085 (3825 525);
PAINT GREEN (3825 525);
DISPLAY INVISIBLE (3825 525);
FORCEPROP 2 LAST VOLTAGE 6.3V
J 2
(3475 575);
DISPLAY 0.553191 (3475 575);
DISPLAY INVISIBLE (3475 575);
FORCEPROP 1 LAST MATERIAL X6S
J 2
(3834 604);
DISPLAY 0.574468 (3834 604);
PAINT GREEN (3834 604);
DISPLAY INVISIBLE (3834 604);
FORCEPROP 2 LAST PACK_TYPE C0201
J 2
(3650 575);
DISPLAY 0.553191 (3650 575);
DISPLAY INVISIBLE (3650 575);
FORCEPROP 2 LAST TOLERANCE 20%
J 2
(3750 575);
DISPLAY 0.553191 (3750 575);
DISPLAY INVISIBLE (3750 575);
FORCEPROP 1 LAST PATH I123
J 2
(3825 525);
DISPLAY 0.723404 (3825 525);
DISPLAY INVISIBLE (3825 525);
FORCEPROP 1 LAST $LOCATION C897
J 0
(4075 600);
DISPLAY 1.021277 (4075 600);
DISPLAY INVISIBLE (4075 600);
FORCEPROP 2 LAST CDS_LOCATION C897
J 0
(4075 600);
DISPLAY 1.021277 (4075 600);
DISPLAY INVISIBLE (4075 600);
FORCEPROP 2 LAST $SEC 1
J 2
(4000 600);
DISPLAY 0.680851 (4000 600);
PAINT MONO (4000 600);
DISPLAY INVISIBLE (4000 600);
FORCEPROP 2 LAST CDS_SEC 1
J 2
(4000 600);
DISPLAY 0.680851 (4000 600);
DISPLAY INVISIBLE (4000 600);
FORCEADD Q_CAP_DIFFBUS..2
R 2
(3825 575);
FORCEPROP 1 LAST PART_NUMBER SP_CH4221MEE01
J 2
(3709 663);
DISPLAY 0.574468 (3709 663);
PAINT GREEN (3709 663);
DISPLAY INVISIBLE (3709 663);
FORCEPROP 2 LAST VALUE DIFF BUS_0.22UF
J 2
(3675 575);
DISPLAY 0.553191 (3675 575);
FORCEPROP 1 LAST $LOCATION C896
J 2
(4059 592);
DISPLAY 0.723404 (4059 592);
PAINT GREEN (4059 592);
FORCEPROP 2 LASTPIN (3900 575) $PN 1
J 0
(3910 585);
DISPLAY 0.808511 (3910 585);
FORCEPROP 2 LASTPIN (3750 575) $PN 2
J 2
(3740 585);
DISPLAY 0.808511 (3740 585);
FORCEPROP 1 LAST PIN_NAMES_ROTATE TRUE
J 2
(3825 575);
DISPLAY 0.489362 (3825 575);
PAINT GREEN (3825 575);
DISPLAY INVISIBLE (3825 575);
FORCEPROP 2 LAST CDS_LIB pure_quanta
J 2
(3825 575);
DISPLAY INVISIBLE (3825 575);
FORCEPROP 1 LAST CDS_LMAN_SYM_OUTLINE -25,50,25,-50
J 2
(3825 575);
DISPLAY 0.468085 (3825 575);
PAINT GREEN (3825 575);
DISPLAY INVISIBLE (3825 575);
FORCEPROP 2 LAST VOLTAGE 6.3V
J 2
(3475 625);
DISPLAY 0.553191 (3475 625);
DISPLAY INVISIBLE (3475 625);
FORCEPROP 1 LAST MATERIAL X6S
J 2
(3834 654);
DISPLAY 0.574468 (3834 654);
PAINT GREEN (3834 654);
DISPLAY INVISIBLE (3834 654);
FORCEPROP 2 LAST PACK_TYPE C0201
J 2
(3650 625);
DISPLAY 0.553191 (3650 625);
DISPLAY INVISIBLE (3650 625);
FORCEPROP 2 LAST TOLERANCE 20%
J 2
(3750 625);
DISPLAY 0.553191 (3750 625);
DISPLAY INVISIBLE (3750 625);
FORCEPROP 1 LAST PATH I124
J 2
(3825 575);
DISPLAY 0.723404 (3825 575);
DISPLAY INVISIBLE (3825 575);
FORCEPROP 1 LAST $LOCATION C896
J 0
(4075 650);
DISPLAY 1.021277 (4075 650);
DISPLAY INVISIBLE (4075 650);
FORCEPROP 2 LAST CDS_LOCATION C896
J 0
(4075 650);
DISPLAY 1.021277 (4075 650);
DISPLAY INVISIBLE (4075 650);
FORCEPROP 2 LAST $SEC 1
J 2
(4000 650);
DISPLAY 0.680851 (4000 650);
PAINT MONO (4000 650);
DISPLAY INVISIBLE (4000 650);
FORCEPROP 2 LAST CDS_SEC 1
J 2
(4000 650);
DISPLAY 0.680851 (4000 650);
DISPLAY INVISIBLE (4000 650);
FORCEADD Q_CAP_DIFFBUS..2
R 2
(3825 725);
FORCEPROP 1 LAST PART_NUMBER SP_CH4221MEE01
J 2
(3709 813);
DISPLAY 0.574468 (3709 813);
PAINT GREEN (3709 813);
DISPLAY INVISIBLE (3709 813);
FORCEPROP 2 LAST VALUE DIFF BUS_0.22UF
J 2
(3675 725);
DISPLAY 0.553191 (3675 725);
FORCEPROP 1 LAST $LOCATION C895
J 2
(4059 742);
DISPLAY 0.723404 (4059 742);
PAINT GREEN (4059 742);
FORCEPROP 2 LASTPIN (3900 725) $PN 1
J 0
(3910 735);
DISPLAY 0.808511 (3910 735);
FORCEPROP 2 LASTPIN (3750 725) $PN 2
J 2
(3740 735);
DISPLAY 0.808511 (3740 735);
FORCEPROP 1 LAST PIN_NAMES_ROTATE TRUE
J 2
(3825 725);
DISPLAY 0.489362 (3825 725);
PAINT GREEN (3825 725);
DISPLAY INVISIBLE (3825 725);
FORCEPROP 1 LAST CDS_LMAN_SYM_OUTLINE -25,50,25,-50
J 2
(3825 725);
DISPLAY 0.468085 (3825 725);
PAINT GREEN (3825 725);
DISPLAY INVISIBLE (3825 725);
FORCEPROP 2 LAST CDS_LIB pure_quanta
J 2
(3825 725);
DISPLAY INVISIBLE (3825 725);
FORCEPROP 2 LAST VOLTAGE 6.3V
J 2
(3475 775);
DISPLAY 0.553191 (3475 775);
DISPLAY INVISIBLE (3475 775);
FORCEPROP 1 LAST MATERIAL X6S
J 2
(3834 804);
DISPLAY 0.574468 (3834 804);
PAINT GREEN (3834 804);
DISPLAY INVISIBLE (3834 804);
FORCEPROP 2 LAST PACK_TYPE C0201
J 2
(3650 775);
DISPLAY 0.553191 (3650 775);
DISPLAY INVISIBLE (3650 775);
FORCEPROP 2 LAST TOLERANCE 20%
J 2
(3750 775);
DISPLAY 0.553191 (3750 775);
DISPLAY INVISIBLE (3750 775);
FORCEPROP 1 LAST PATH I125
J 2
(3825 725);
DISPLAY 0.723404 (3825 725);
DISPLAY INVISIBLE (3825 725);
FORCEPROP 1 LAST $LOCATION C895
J 0
(4075 800);
DISPLAY 1.021277 (4075 800);
DISPLAY INVISIBLE (4075 800);
FORCEPROP 2 LAST CDS_LOCATION C895
J 0
(4075 800);
DISPLAY 1.021277 (4075 800);
DISPLAY INVISIBLE (4075 800);
FORCEPROP 2 LAST $SEC 1
J 2
(4000 800);
DISPLAY 0.680851 (4000 800);
PAINT MONO (4000 800);
DISPLAY INVISIBLE (4000 800);
FORCEPROP 2 LAST CDS_SEC 1
J 2
(4000 800);
DISPLAY 0.680851 (4000 800);
DISPLAY INVISIBLE (4000 800);
FORCEADD Q_CAP_DIFFBUS..2
R 2
(3825 775);
FORCEPROP 1 LAST PART_NUMBER SP_CH4221MEE01
J 2
(3709 863);
DISPLAY 0.574468 (3709 863);
PAINT GREEN (3709 863);
DISPLAY INVISIBLE (3709 863);
FORCEPROP 2 LAST VALUE DIFF BUS_0.22UF
J 2
(3675 775);
DISPLAY 0.553191 (3675 775);
FORCEPROP 1 LAST $LOCATION C894
J 2
(4059 792);
DISPLAY 0.723404 (4059 792);
PAINT GREEN (4059 792);
FORCEPROP 2 LASTPIN (3900 775) $PN 1
J 0
(3910 785);
DISPLAY 0.808511 (3910 785);
FORCEPROP 2 LASTPIN (3750 775) $PN 2
J 2
(3740 785);
DISPLAY 0.808511 (3740 785);
FORCEPROP 1 LAST PIN_NAMES_ROTATE TRUE
J 2
(3825 775);
DISPLAY 0.489362 (3825 775);
PAINT GREEN (3825 775);
DISPLAY INVISIBLE (3825 775);
FORCEPROP 1 LAST CDS_LMAN_SYM_OUTLINE -25,50,25,-50
J 2
(3825 775);
DISPLAY 0.468085 (3825 775);
PAINT GREEN (3825 775);
DISPLAY INVISIBLE (3825 775);
FORCEPROP 2 LAST CDS_LIB pure_quanta
J 2
(3825 775);
DISPLAY INVISIBLE (3825 775);
FORCEPROP 2 LAST VOLTAGE 6.3V
J 2
(3475 825);
DISPLAY 0.553191 (3475 825);
DISPLAY INVISIBLE (3475 825);
FORCEPROP 1 LAST MATERIAL X6S
J 2
(3834 854);
DISPLAY 0.574468 (3834 854);
PAINT GREEN (3834 854);
DISPLAY INVISIBLE (3834 854);
FORCEPROP 2 LAST PACK_TYPE C0201
J 2
(3650 825);
DISPLAY 0.553191 (3650 825);
DISPLAY INVISIBLE (3650 825);
FORCEPROP 2 LAST TOLERANCE 20%
J 2
(3750 825);
DISPLAY 0.553191 (3750 825);
DISPLAY INVISIBLE (3750 825);
FORCEPROP 1 LAST PATH I126
J 2
(3825 775);
DISPLAY 0.723404 (3825 775);
DISPLAY INVISIBLE (3825 775);
FORCEPROP 1 LAST $LOCATION C894
J 0
(4075 850);
DISPLAY 1.021277 (4075 850);
DISPLAY INVISIBLE (4075 850);
FORCEPROP 2 LAST CDS_LOCATION C894
J 0
(4075 850);
DISPLAY 1.021277 (4075 850);
DISPLAY INVISIBLE (4075 850);
FORCEPROP 2 LAST $SEC 1
J 2
(4000 850);
DISPLAY 0.680851 (4000 850);
PAINT MONO (4000 850);
DISPLAY INVISIBLE (4000 850);
FORCEPROP 2 LAST CDS_SEC 1
J 2
(4000 850);
DISPLAY 0.680851 (4000 850);
DISPLAY INVISIBLE (4000 850);
FORCEADD Q_CAP_DIFFBUS..2
R 2
(3825 975);
FORCEPROP 1 LAST PART_NUMBER SP_CH4221MEE01
J 2
(3709 1063);
DISPLAY 0.574468 (3709 1063);
PAINT GREEN (3709 1063);
DISPLAY INVISIBLE (3709 1063);
FORCEPROP 2 LAST VALUE DIFF BUS_0.22UF
J 2
(3675 975);
DISPLAY 0.553191 (3675 975);
FORCEPROP 1 LAST $LOCATION C892
J 2
(4059 992);
DISPLAY 0.723404 (4059 992);
PAINT GREEN (4059 992);
FORCEPROP 2 LASTPIN (3900 975) $PN 1
J 0
(3910 985);
DISPLAY 0.808511 (3910 985);
FORCEPROP 2 LASTPIN (3750 975) $PN 2
J 2
(3740 985);
DISPLAY 0.808511 (3740 985);
FORCEPROP 1 LAST PIN_NAMES_ROTATE TRUE
J 2
(3825 975);
DISPLAY 0.489362 (3825 975);
PAINT GREEN (3825 975);
DISPLAY INVISIBLE (3825 975);
FORCEPROP 2 LAST CDS_LIB pure_quanta
J 2
(3825 975);
DISPLAY INVISIBLE (3825 975);
FORCEPROP 1 LAST CDS_LMAN_SYM_OUTLINE -25,50,25,-50
J 2
(3825 975);
DISPLAY 0.468085 (3825 975);
PAINT GREEN (3825 975);
DISPLAY INVISIBLE (3825 975);
FORCEPROP 2 LAST VOLTAGE 6.3V
J 2
(3475 1025);
DISPLAY 0.553191 (3475 1025);
DISPLAY INVISIBLE (3475 1025);
FORCEPROP 1 LAST MATERIAL X6S
J 2
(3834 1054);
DISPLAY 0.574468 (3834 1054);
PAINT GREEN (3834 1054);
DISPLAY INVISIBLE (3834 1054);
FORCEPROP 2 LAST PACK_TYPE C0201
J 2
(3650 1025);
DISPLAY 0.553191 (3650 1025);
DISPLAY INVISIBLE (3650 1025);
FORCEPROP 2 LAST TOLERANCE 20%
J 2
(3750 1025);
DISPLAY 0.553191 (3750 1025);
DISPLAY INVISIBLE (3750 1025);
FORCEPROP 1 LAST PATH I127
J 2
(3825 975);
DISPLAY 0.723404 (3825 975);
DISPLAY INVISIBLE (3825 975);
FORCEPROP 1 LAST $LOCATION C892
J 0
(4075 1050);
DISPLAY 1.021277 (4075 1050);
DISPLAY INVISIBLE (4075 1050);
FORCEPROP 2 LAST CDS_LOCATION C892
J 0
(4075 1050);
DISPLAY 1.021277 (4075 1050);
DISPLAY INVISIBLE (4075 1050);
FORCEPROP 2 LAST $SEC 1
J 2
(4000 1050);
DISPLAY 0.680851 (4000 1050);
PAINT MONO (4000 1050);
DISPLAY INVISIBLE (4000 1050);
FORCEPROP 2 LAST CDS_SEC 1
J 2
(4000 1050);
DISPLAY 0.680851 (4000 1050);
DISPLAY INVISIBLE (4000 1050);
FORCEADD Q_CAP_DIFFBUS..2
R 2
(3825 925);
FORCEPROP 1 LAST PART_NUMBER SP_CH4221MEE01
J 2
(3709 1013);
DISPLAY 0.574468 (3709 1013);
PAINT GREEN (3709 1013);
DISPLAY INVISIBLE (3709 1013);
FORCEPROP 2 LAST VALUE DIFF BUS_0.22UF
J 2
(3675 925);
DISPLAY 0.553191 (3675 925);
FORCEPROP 1 LAST $LOCATION C893
J 2
(4059 942);
DISPLAY 0.723404 (4059 942);
PAINT GREEN (4059 942);
FORCEPROP 2 LASTPIN (3900 925) $PN 1
J 0
(3910 935);
DISPLAY 0.808511 (3910 935);
FORCEPROP 2 LASTPIN (3750 925) $PN 2
J 2
(3740 935);
DISPLAY 0.808511 (3740 935);
FORCEPROP 1 LAST PIN_NAMES_ROTATE TRUE
J 2
(3825 925);
DISPLAY 0.489362 (3825 925);
PAINT GREEN (3825 925);
DISPLAY INVISIBLE (3825 925);
FORCEPROP 2 LAST CDS_LIB pure_quanta
J 2
(3825 925);
DISPLAY INVISIBLE (3825 925);
FORCEPROP 1 LAST CDS_LMAN_SYM_OUTLINE -25,50,25,-50
J 2
(3825 925);
DISPLAY 0.468085 (3825 925);
PAINT GREEN (3825 925);
DISPLAY INVISIBLE (3825 925);
FORCEPROP 2 LAST VOLTAGE 6.3V
J 2
(3475 975);
DISPLAY 0.553191 (3475 975);
DISPLAY INVISIBLE (3475 975);
FORCEPROP 1 LAST MATERIAL X6S
J 2
(3834 1004);
DISPLAY 0.574468 (3834 1004);
PAINT GREEN (3834 1004);
DISPLAY INVISIBLE (3834 1004);
FORCEPROP 2 LAST PACK_TYPE C0201
J 2
(3650 975);
DISPLAY 0.553191 (3650 975);
DISPLAY INVISIBLE (3650 975);
FORCEPROP 2 LAST TOLERANCE 20%
J 2
(3750 975);
DISPLAY 0.553191 (3750 975);
DISPLAY INVISIBLE (3750 975);
FORCEPROP 1 LAST PATH I128
J 2
(3825 925);
DISPLAY 0.723404 (3825 925);
DISPLAY INVISIBLE (3825 925);
FORCEPROP 1 LAST $LOCATION C893
J 0
(4075 1000);
DISPLAY 1.021277 (4075 1000);
DISPLAY INVISIBLE (4075 1000);
FORCEPROP 2 LAST CDS_LOCATION C893
J 0
(4075 1000);
DISPLAY 1.021277 (4075 1000);
DISPLAY INVISIBLE (4075 1000);
FORCEPROP 2 LAST $SEC 1
J 2
(4000 1000);
DISPLAY 0.680851 (4000 1000);
PAINT MONO (4000 1000);
DISPLAY INVISIBLE (4000 1000);
FORCEPROP 2 LAST CDS_SEC 1
J 2
(4000 1000);
DISPLAY 0.680851 (4000 1000);
DISPLAY INVISIBLE (4000 1000);
FORCEADD TAP..1
R 2
(3100 1175);
FORCEPROP 3 LASTPIN (3150 1175) SIG_NAME P5E_CPU0_PE3_TX_DN<5>
J 0
(3160 1185);
DISPLAY 0.659574 (3160 1185);
PAINT MONO (3160 1185);
DISPLAY INVISIBLE (3160 1185);
FORCEPROP 1 LASTPIN (3150 1175) BN 5
J 2
(3162 1183);
DISPLAY 0.680851 (3162 1183);
PAINT GREEN (3162 1183);
FORCEPROP 2 LAST CDS_LIB standard
J 0
(3100 1175);
DISPLAY INVISIBLE (3100 1175);
FORCEPROP 1 LAST BODY_TYPE PLUMBING
J 2
(3100 1225);
DISPLAY 0.872340 (3100 1225);
PAINT GREEN (3100 1225);
DISPLAY INVISIBLE (3100 1225);
FORCEPROP 1 LAST HDL_TAP TRUE
J 2
(2775 1050);
DISPLAY 0.872340 (2775 1050);
DISPLAY INVISIBLE (2775 1050);
FORCEPROP 1 LAST PATH I129
J 2
(3102 1175);
DISPLAY 0.872340 (3102 1175);
PAINT GREEN (3102 1175);
DISPLAY INVISIBLE (3102 1175);
FORCEADD TAP..1
R 2
(-1375 775);
FORCEPROP 3 LASTPIN (-1325 775) SIG_NAME P5E_CPU0_PE1_TX_DN<3>
J 0
(-1315 785);
DISPLAY 0.659574 (-1315 785);
PAINT MONO (-1315 785);
DISPLAY INVISIBLE (-1315 785);
FORCEPROP 1 LASTPIN (-1325 775) BN 3
J 2
(-1313 783);
DISPLAY 0.680851 (-1313 783);
PAINT GREEN (-1313 783);
FORCEPROP 2 LAST CDS_LIB standard
J 0
(-1375 775);
DISPLAY INVISIBLE (-1375 775);
FORCEPROP 1 LAST BODY_TYPE PLUMBING
J 2
(-1375 825);
DISPLAY 0.872340 (-1375 825);
PAINT GREEN (-1375 825);
DISPLAY INVISIBLE (-1375 825);
FORCEPROP 1 LAST HDL_TAP TRUE
J 2
(-1700 650);
DISPLAY 0.872340 (-1700 650);
DISPLAY INVISIBLE (-1700 650);
FORCEPROP 1 LAST PATH I13
J 2
(-1373 775);
DISPLAY 0.872340 (-1373 775);
PAINT GREEN (-1373 775);
DISPLAY INVISIBLE (-1373 775);
FORCEADD TAP..1
R 2
(3100 1375);
FORCEPROP 3 LASTPIN (3150 1375) SIG_NAME P5E_CPU0_PE3_TX_DN<6>
J 0
(3160 1385);
DISPLAY 0.659574 (3160 1385);
PAINT MONO (3160 1385);
DISPLAY INVISIBLE (3160 1385);
FORCEPROP 1 LASTPIN (3150 1375) BN 6
J 2
(3162 1383);
DISPLAY 0.680851 (3162 1383);
PAINT GREEN (3162 1383);
FORCEPROP 2 LAST CDS_LIB standard
J 0
(3100 1375);
DISPLAY INVISIBLE (3100 1375);
FORCEPROP 1 LAST BODY_TYPE PLUMBING
J 2
(3100 1425);
DISPLAY 0.872340 (3100 1425);
PAINT GREEN (3100 1425);
DISPLAY INVISIBLE (3100 1425);
FORCEPROP 1 LAST HDL_TAP TRUE
J 2
(2775 1250);
DISPLAY 0.872340 (2775 1250);
DISPLAY INVISIBLE (2775 1250);
FORCEPROP 1 LAST PATH I130
J 2
(3102 1375);
DISPLAY 0.872340 (3102 1375);
PAINT GREEN (3102 1375);
DISPLAY INVISIBLE (3102 1375);
FORCEADD TAP..1
R 2
(3100 1575);
FORCEPROP 3 LASTPIN (3150 1575) SIG_NAME P5E_CPU0_PE3_TX_DN<7>
J 0
(3160 1585);
DISPLAY 0.659574 (3160 1585);
PAINT MONO (3160 1585);
DISPLAY INVISIBLE (3160 1585);
FORCEPROP 1 LASTPIN (3150 1575) BN 7
J 2
(3162 1583);
DISPLAY 0.680851 (3162 1583);
PAINT GREEN (3162 1583);
FORCEPROP 2 LAST CDS_LIB standard
J 0
(3100 1575);
DISPLAY INVISIBLE (3100 1575);
FORCEPROP 1 LAST BODY_TYPE PLUMBING
J 2
(3100 1625);
DISPLAY 0.872340 (3100 1625);
PAINT GREEN (3100 1625);
DISPLAY INVISIBLE (3100 1625);
FORCEPROP 1 LAST HDL_TAP TRUE
J 2
(2775 1450);
DISPLAY 0.872340 (2775 1450);
DISPLAY INVISIBLE (2775 1450);
FORCEPROP 1 LAST PATH I131
J 2
(3102 1575);
DISPLAY 0.872340 (3102 1575);
PAINT GREEN (3102 1575);
DISPLAY INVISIBLE (3102 1575);
FORCEADD Q_CAP_DIFFBUS..2
R 2
(3825 1125);
FORCEPROP 1 LAST PART_NUMBER SP_CH4221MEE01
J 2
(3709 1213);
DISPLAY 0.574468 (3709 1213);
PAINT GREEN (3709 1213);
DISPLAY INVISIBLE (3709 1213);
FORCEPROP 2 LAST VALUE DIFF BUS_0.22UF
J 2
(3675 1125);
DISPLAY 0.553191 (3675 1125);
FORCEPROP 1 LAST $LOCATION C891
J 2
(4059 1142);
DISPLAY 0.723404 (4059 1142);
PAINT GREEN (4059 1142);
FORCEPROP 2 LASTPIN (3900 1125) $PN 1
J 0
(3910 1135);
DISPLAY 0.808511 (3910 1135);
FORCEPROP 2 LASTPIN (3750 1125) $PN 2
J 2
(3740 1135);
DISPLAY 0.808511 (3740 1135);
FORCEPROP 1 LAST PIN_NAMES_ROTATE TRUE
J 2
(3825 1125);
DISPLAY 0.489362 (3825 1125);
PAINT GREEN (3825 1125);
DISPLAY INVISIBLE (3825 1125);
FORCEPROP 2 LAST CDS_LIB pure_quanta
J 2
(3825 1125);
DISPLAY INVISIBLE (3825 1125);
FORCEPROP 1 LAST CDS_LMAN_SYM_OUTLINE -25,50,25,-50
J 2
(3825 1125);
DISPLAY 0.468085 (3825 1125);
PAINT GREEN (3825 1125);
DISPLAY INVISIBLE (3825 1125);
FORCEPROP 2 LAST VOLTAGE 6.3V
J 2
(3475 1175);
DISPLAY 0.553191 (3475 1175);
DISPLAY INVISIBLE (3475 1175);
FORCEPROP 1 LAST MATERIAL X6S
J 2
(3834 1204);
DISPLAY 0.574468 (3834 1204);
PAINT GREEN (3834 1204);
DISPLAY INVISIBLE (3834 1204);
FORCEPROP 2 LAST PACK_TYPE C0201
J 2
(3650 1175);
DISPLAY 0.553191 (3650 1175);
DISPLAY INVISIBLE (3650 1175);
FORCEPROP 2 LAST TOLERANCE 20%
J 2
(3750 1175);
DISPLAY 0.553191 (3750 1175);
DISPLAY INVISIBLE (3750 1175);
FORCEPROP 1 LAST PATH I132
J 2
(3825 1125);
DISPLAY 0.723404 (3825 1125);
DISPLAY INVISIBLE (3825 1125);
FORCEPROP 1 LAST $LOCATION C891
J 0
(4075 1200);
DISPLAY 1.021277 (4075 1200);
DISPLAY INVISIBLE (4075 1200);
FORCEPROP 2 LAST CDS_LOCATION C891
J 0
(4075 1200);
DISPLAY 1.021277 (4075 1200);
DISPLAY INVISIBLE (4075 1200);
FORCEPROP 2 LAST $SEC 1
J 2
(4000 1200);
DISPLAY 0.680851 (4000 1200);
PAINT MONO (4000 1200);
DISPLAY INVISIBLE (4000 1200);
FORCEPROP 2 LAST CDS_SEC 1
J 2
(4000 1200);
DISPLAY 0.680851 (4000 1200);
DISPLAY INVISIBLE (4000 1200);
FORCEADD Q_CAP_DIFFBUS..2
R 2
(3825 1175);
FORCEPROP 1 LAST PART_NUMBER SP_CH4221MEE01
J 2
(3709 1263);
DISPLAY 0.574468 (3709 1263);
PAINT GREEN (3709 1263);
DISPLAY INVISIBLE (3709 1263);
FORCEPROP 2 LAST VALUE DIFF BUS_0.22UF
J 2
(3675 1175);
DISPLAY 0.553191 (3675 1175);
FORCEPROP 1 LAST $LOCATION C890
J 2
(4059 1192);
DISPLAY 0.723404 (4059 1192);
PAINT GREEN (4059 1192);
FORCEPROP 2 LASTPIN (3900 1175) $PN 1
J 0
(3910 1185);
DISPLAY 0.808511 (3910 1185);
FORCEPROP 2 LASTPIN (3750 1175) $PN 2
J 2
(3740 1185);
DISPLAY 0.808511 (3740 1185);
FORCEPROP 1 LAST PIN_NAMES_ROTATE TRUE
J 2
(3825 1175);
DISPLAY 0.489362 (3825 1175);
PAINT GREEN (3825 1175);
DISPLAY INVISIBLE (3825 1175);
FORCEPROP 2 LAST CDS_LIB pure_quanta
J 2
(3825 1175);
DISPLAY INVISIBLE (3825 1175);
FORCEPROP 1 LAST CDS_LMAN_SYM_OUTLINE -25,50,25,-50
J 2
(3825 1175);
DISPLAY 0.468085 (3825 1175);
PAINT GREEN (3825 1175);
DISPLAY INVISIBLE (3825 1175);
FORCEPROP 2 LAST VOLTAGE 6.3V
J 2
(3475 1225);
DISPLAY 0.553191 (3475 1225);
DISPLAY INVISIBLE (3475 1225);
FORCEPROP 1 LAST MATERIAL X6S
J 2
(3834 1254);
DISPLAY 0.574468 (3834 1254);
PAINT GREEN (3834 1254);
DISPLAY INVISIBLE (3834 1254);
FORCEPROP 2 LAST PACK_TYPE C0201
J 2
(3650 1225);
DISPLAY 0.553191 (3650 1225);
DISPLAY INVISIBLE (3650 1225);
FORCEPROP 2 LAST TOLERANCE 20%
J 2
(3750 1225);
DISPLAY 0.553191 (3750 1225);
DISPLAY INVISIBLE (3750 1225);
FORCEPROP 1 LAST PATH I133
J 2
(3825 1175);
DISPLAY 0.723404 (3825 1175);
DISPLAY INVISIBLE (3825 1175);
FORCEPROP 1 LAST $LOCATION C890
J 0
(4075 1250);
DISPLAY 1.021277 (4075 1250);
DISPLAY INVISIBLE (4075 1250);
FORCEPROP 2 LAST CDS_LOCATION C890
J 0
(4075 1250);
DISPLAY 1.021277 (4075 1250);
DISPLAY INVISIBLE (4075 1250);
FORCEPROP 2 LAST $SEC 1
J 2
(4000 1250);
DISPLAY 0.680851 (4000 1250);
PAINT MONO (4000 1250);
DISPLAY INVISIBLE (4000 1250);
FORCEPROP 2 LAST CDS_SEC 1
J 2
(4000 1250);
DISPLAY 0.680851 (4000 1250);
DISPLAY INVISIBLE (4000 1250);
FORCEADD Q_CAP_DIFFBUS..2
R 2
(3825 1325);
FORCEPROP 1 LAST PART_NUMBER SP_CH4221MEE01
J 2
(3709 1413);
DISPLAY 0.574468 (3709 1413);
PAINT GREEN (3709 1413);
DISPLAY INVISIBLE (3709 1413);
FORCEPROP 2 LAST VALUE DIFF BUS_0.22UF
J 2
(3675 1325);
DISPLAY 0.553191 (3675 1325);
FORCEPROP 1 LAST $LOCATION C889
J 2
(4059 1342);
DISPLAY 0.723404 (4059 1342);
PAINT GREEN (4059 1342);
FORCEPROP 2 LASTPIN (3900 1325) $PN 1
J 0
(3910 1335);
DISPLAY 0.808511 (3910 1335);
FORCEPROP 2 LASTPIN (3750 1325) $PN 2
J 2
(3740 1335);
DISPLAY 0.808511 (3740 1335);
FORCEPROP 1 LAST PIN_NAMES_ROTATE TRUE
J 2
(3825 1325);
DISPLAY 0.489362 (3825 1325);
PAINT GREEN (3825 1325);
DISPLAY INVISIBLE (3825 1325);
FORCEPROP 2 LAST CDS_LIB pure_quanta
J 2
(3825 1325);
DISPLAY INVISIBLE (3825 1325);
FORCEPROP 1 LAST CDS_LMAN_SYM_OUTLINE -25,50,25,-50
J 2
(3825 1325);
DISPLAY 0.468085 (3825 1325);
PAINT GREEN (3825 1325);
DISPLAY INVISIBLE (3825 1325);
FORCEPROP 2 LAST VOLTAGE 6.3V
J 2
(3475 1375);
DISPLAY 0.553191 (3475 1375);
DISPLAY INVISIBLE (3475 1375);
FORCEPROP 1 LAST MATERIAL X6S
J 2
(3834 1404);
DISPLAY 0.574468 (3834 1404);
PAINT GREEN (3834 1404);
DISPLAY INVISIBLE (3834 1404);
FORCEPROP 2 LAST PACK_TYPE C0201
J 2
(3650 1375);
DISPLAY 0.553191 (3650 1375);
DISPLAY INVISIBLE (3650 1375);
FORCEPROP 2 LAST TOLERANCE 20%
J 2
(3750 1375);
DISPLAY 0.553191 (3750 1375);
DISPLAY INVISIBLE (3750 1375);
FORCEPROP 1 LAST PATH I134
J 2
(3825 1325);
DISPLAY 0.723404 (3825 1325);
DISPLAY INVISIBLE (3825 1325);
FORCEPROP 1 LAST $LOCATION C889
J 0
(4075 1400);
DISPLAY 1.021277 (4075 1400);
DISPLAY INVISIBLE (4075 1400);
FORCEPROP 2 LAST CDS_LOCATION C889
J 0
(4075 1400);
DISPLAY 1.021277 (4075 1400);
DISPLAY INVISIBLE (4075 1400);
FORCEPROP 2 LAST $SEC 1
J 2
(4000 1400);
DISPLAY 0.680851 (4000 1400);
PAINT MONO (4000 1400);
DISPLAY INVISIBLE (4000 1400);
FORCEPROP 2 LAST CDS_SEC 1
J 2
(4000 1400);
DISPLAY 0.680851 (4000 1400);
DISPLAY INVISIBLE (4000 1400);
FORCEADD Q_CAP_DIFFBUS..2
R 2
(3825 1375);
FORCEPROP 1 LAST PART_NUMBER SP_CH4221MEE01
J 2
(3709 1463);
DISPLAY 0.574468 (3709 1463);
PAINT GREEN (3709 1463);
DISPLAY INVISIBLE (3709 1463);
FORCEPROP 2 LAST VALUE DIFF BUS_0.22UF
J 2
(3675 1375);
DISPLAY 0.553191 (3675 1375);
FORCEPROP 1 LAST $LOCATION C888
J 2
(4059 1392);
DISPLAY 0.723404 (4059 1392);
PAINT GREEN (4059 1392);
FORCEPROP 2 LASTPIN (3900 1375) $PN 1
J 0
(3910 1385);
DISPLAY 0.808511 (3910 1385);
FORCEPROP 2 LASTPIN (3750 1375) $PN 2
J 2
(3740 1385);
DISPLAY 0.808511 (3740 1385);
FORCEPROP 1 LAST PIN_NAMES_ROTATE TRUE
J 2
(3825 1375);
DISPLAY 0.489362 (3825 1375);
PAINT GREEN (3825 1375);
DISPLAY INVISIBLE (3825 1375);
FORCEPROP 2 LAST CDS_LIB pure_quanta
J 2
(3825 1375);
DISPLAY INVISIBLE (3825 1375);
FORCEPROP 1 LAST CDS_LMAN_SYM_OUTLINE -25,50,25,-50
J 2
(3825 1375);
DISPLAY 0.468085 (3825 1375);
PAINT GREEN (3825 1375);
DISPLAY INVISIBLE (3825 1375);
FORCEPROP 2 LAST VOLTAGE 6.3V
J 2
(3475 1425);
DISPLAY 0.553191 (3475 1425);
DISPLAY INVISIBLE (3475 1425);
FORCEPROP 1 LAST MATERIAL X6S
J 2
(3834 1454);
DISPLAY 0.574468 (3834 1454);
PAINT GREEN (3834 1454);
DISPLAY INVISIBLE (3834 1454);
FORCEPROP 2 LAST PACK_TYPE C0201
J 2
(3650 1425);
DISPLAY 0.553191 (3650 1425);
DISPLAY INVISIBLE (3650 1425);
FORCEPROP 2 LAST TOLERANCE 20%
J 2
(3750 1425);
DISPLAY 0.553191 (3750 1425);
DISPLAY INVISIBLE (3750 1425);
FORCEPROP 1 LAST PATH I135
J 2
(3825 1375);
DISPLAY 0.723404 (3825 1375);
DISPLAY INVISIBLE (3825 1375);
FORCEPROP 1 LAST $LOCATION C888
J 0
(4075 1450);
DISPLAY 1.021277 (4075 1450);
DISPLAY INVISIBLE (4075 1450);
FORCEPROP 2 LAST CDS_LOCATION C888
J 0
(4075 1450);
DISPLAY 1.021277 (4075 1450);
DISPLAY INVISIBLE (4075 1450);
FORCEPROP 2 LAST $SEC 1
J 2
(4000 1450);
DISPLAY 0.680851 (4000 1450);
PAINT MONO (4000 1450);
DISPLAY INVISIBLE (4000 1450);
FORCEPROP 2 LAST CDS_SEC 1
J 2
(4000 1450);
DISPLAY 0.680851 (4000 1450);
DISPLAY INVISIBLE (4000 1450);
FORCEADD Q_CAP_DIFFBUS..2
R 2
(3825 1525);
FORCEPROP 1 LAST PART_NUMBER SP_CH4221MEE01
J 2
(3709 1613);
DISPLAY 0.574468 (3709 1613);
PAINT GREEN (3709 1613);
DISPLAY INVISIBLE (3709 1613);
FORCEPROP 2 LAST VALUE DIFF BUS_0.22UF
J 2
(3675 1525);
DISPLAY 0.553191 (3675 1525);
FORCEPROP 1 LAST $LOCATION C887
J 2
(4059 1542);
DISPLAY 0.723404 (4059 1542);
PAINT GREEN (4059 1542);
FORCEPROP 2 LASTPIN (3900 1525) $PN 1
J 0
(3910 1535);
DISPLAY 0.808511 (3910 1535);
FORCEPROP 2 LASTPIN (3750 1525) $PN 2
J 2
(3740 1535);
DISPLAY 0.808511 (3740 1535);
FORCEPROP 1 LAST PIN_NAMES_ROTATE TRUE
J 2
(3825 1525);
DISPLAY 0.489362 (3825 1525);
PAINT GREEN (3825 1525);
DISPLAY INVISIBLE (3825 1525);
FORCEPROP 2 LAST CDS_LIB pure_quanta
J 2
(3825 1525);
DISPLAY INVISIBLE (3825 1525);
FORCEPROP 1 LAST CDS_LMAN_SYM_OUTLINE -25,50,25,-50
J 2
(3825 1525);
DISPLAY 0.468085 (3825 1525);
PAINT GREEN (3825 1525);
DISPLAY INVISIBLE (3825 1525);
FORCEPROP 2 LAST VOLTAGE 6.3V
J 2
(3475 1575);
DISPLAY 0.553191 (3475 1575);
DISPLAY INVISIBLE (3475 1575);
FORCEPROP 1 LAST MATERIAL X6S
J 2
(3834 1604);
DISPLAY 0.574468 (3834 1604);
PAINT GREEN (3834 1604);
DISPLAY INVISIBLE (3834 1604);
FORCEPROP 2 LAST PACK_TYPE C0201
J 2
(3650 1575);
DISPLAY 0.553191 (3650 1575);
DISPLAY INVISIBLE (3650 1575);
FORCEPROP 2 LAST TOLERANCE 20%
J 2
(3750 1575);
DISPLAY 0.553191 (3750 1575);
DISPLAY INVISIBLE (3750 1575);
FORCEPROP 1 LAST PATH I136
J 2
(3825 1525);
DISPLAY 0.723404 (3825 1525);
DISPLAY INVISIBLE (3825 1525);
FORCEPROP 1 LAST $LOCATION C887
J 0
(4075 1600);
DISPLAY 1.021277 (4075 1600);
DISPLAY INVISIBLE (4075 1600);
FORCEPROP 2 LAST CDS_LOCATION C887
J 0
(4075 1600);
DISPLAY 1.021277 (4075 1600);
DISPLAY INVISIBLE (4075 1600);
FORCEPROP 2 LAST $SEC 1
J 2
(4000 1600);
DISPLAY 0.680851 (4000 1600);
PAINT MONO (4000 1600);
DISPLAY INVISIBLE (4000 1600);
FORCEPROP 2 LAST CDS_SEC 1
J 2
(4000 1600);
DISPLAY 0.680851 (4000 1600);
DISPLAY INVISIBLE (4000 1600);
FORCEADD Q_CAP_DIFFBUS..2
R 2
(3825 1575);
FORCEPROP 1 LAST PART_NUMBER SP_CH4221MEE01
J 2
(3709 1663);
DISPLAY 0.574468 (3709 1663);
PAINT GREEN (3709 1663);
DISPLAY INVISIBLE (3709 1663);
FORCEPROP 2 LAST VALUE DIFF BUS_0.22UF
J 2
(3675 1575);
DISPLAY 0.553191 (3675 1575);
FORCEPROP 1 LAST $LOCATION C886
J 2
(4059 1592);
DISPLAY 0.723404 (4059 1592);
PAINT GREEN (4059 1592);
FORCEPROP 2 LASTPIN (3900 1575) $PN 1
J 0
(3910 1585);
DISPLAY 0.808511 (3910 1585);
FORCEPROP 2 LASTPIN (3750 1575) $PN 2
J 2
(3740 1585);
DISPLAY 0.808511 (3740 1585);
FORCEPROP 1 LAST PIN_NAMES_ROTATE TRUE
J 2
(3825 1575);
DISPLAY 0.489362 (3825 1575);
PAINT GREEN (3825 1575);
DISPLAY INVISIBLE (3825 1575);
FORCEPROP 1 LAST CDS_LMAN_SYM_OUTLINE -25,50,25,-50
J 2
(3825 1575);
DISPLAY 0.468085 (3825 1575);
PAINT GREEN (3825 1575);
DISPLAY INVISIBLE (3825 1575);
FORCEPROP 2 LAST CDS_LIB pure_quanta
J 2
(3825 1575);
DISPLAY INVISIBLE (3825 1575);
FORCEPROP 2 LAST VOLTAGE 6.3V
J 2
(3475 1625);
DISPLAY 0.553191 (3475 1625);
DISPLAY INVISIBLE (3475 1625);
FORCEPROP 1 LAST MATERIAL X6S
J 2
(3834 1654);
DISPLAY 0.574468 (3834 1654);
PAINT GREEN (3834 1654);
DISPLAY INVISIBLE (3834 1654);
FORCEPROP 2 LAST PACK_TYPE C0201
J 2
(3650 1625);
DISPLAY 0.553191 (3650 1625);
DISPLAY INVISIBLE (3650 1625);
FORCEPROP 2 LAST TOLERANCE 20%
J 2
(3750 1625);
DISPLAY 0.553191 (3750 1625);
DISPLAY INVISIBLE (3750 1625);
FORCEPROP 1 LAST PATH I137
J 2
(3825 1575);
DISPLAY 0.723404 (3825 1575);
DISPLAY INVISIBLE (3825 1575);
FORCEPROP 1 LAST $LOCATION C886
J 0
(4075 1650);
DISPLAY 1.021277 (4075 1650);
DISPLAY INVISIBLE (4075 1650);
FORCEPROP 2 LAST CDS_LOCATION C886
J 0
(4075 1650);
DISPLAY 1.021277 (4075 1650);
DISPLAY INVISIBLE (4075 1650);
FORCEPROP 2 LAST $SEC 1
J 2
(4000 1650);
DISPLAY 0.680851 (4000 1650);
PAINT MONO (4000 1650);
DISPLAY INVISIBLE (4000 1650);
FORCEPROP 2 LAST CDS_SEC 1
J 2
(4000 1650);
DISPLAY 0.680851 (4000 1650);
DISPLAY INVISIBLE (4000 1650);
FORCEADD TAP..1
R 2
(2850 2100);
FORCEPROP 3 LASTPIN (2900 2100) SIG_NAME P5E_CPU0_PE3_TX_DP<8>
J 0
(2910 2110);
DISPLAY 0.659574 (2910 2110);
PAINT MONO (2910 2110);
DISPLAY INVISIBLE (2910 2110);
FORCEPROP 1 LASTPIN (2900 2100) BN 8
J 2
(2912 2108);
DISPLAY 0.680851 (2912 2108);
PAINT GREEN (2912 2108);
FORCEPROP 2 LAST CDS_LIB standard
J 0
(2850 2100);
DISPLAY INVISIBLE (2850 2100);
FORCEPROP 1 LAST BODY_TYPE PLUMBING
J 2
(2850 2150);
DISPLAY 0.872340 (2850 2150);
PAINT GREEN (2850 2150);
DISPLAY INVISIBLE (2850 2150);
FORCEPROP 1 LAST HDL_TAP TRUE
J 2
(2525 1975);
DISPLAY 0.872340 (2525 1975);
DISPLAY INVISIBLE (2525 1975);
FORCEPROP 1 LAST PATH I138
J 2
(2852 2100);
DISPLAY 0.872340 (2852 2100);
PAINT GREEN (2852 2100);
DISPLAY INVISIBLE (2852 2100);
FORCEADD TAP..1
R 2
(2850 2300);
FORCEPROP 3 LASTPIN (2900 2300) SIG_NAME P5E_CPU0_PE3_TX_DP<9>
J 0
(2910 2310);
DISPLAY 0.659574 (2910 2310);
PAINT MONO (2910 2310);
DISPLAY INVISIBLE (2910 2310);
FORCEPROP 1 LASTPIN (2900 2300) BN 9
J 2
(2912 2308);
DISPLAY 0.680851 (2912 2308);
PAINT GREEN (2912 2308);
FORCEPROP 2 LAST CDS_LIB standard
J 0
(2850 2300);
DISPLAY INVISIBLE (2850 2300);
FORCEPROP 1 LAST BODY_TYPE PLUMBING
J 2
(2850 2350);
DISPLAY 0.872340 (2850 2350);
PAINT GREEN (2850 2350);
DISPLAY INVISIBLE (2850 2350);
FORCEPROP 1 LAST HDL_TAP TRUE
J 2
(2525 2175);
DISPLAY 0.872340 (2525 2175);
DISPLAY INVISIBLE (2525 2175);
FORCEPROP 1 LAST PATH I139
J 2
(2852 2300);
DISPLAY 0.872340 (2852 2300);
PAINT GREEN (2852 2300);
DISPLAY INVISIBLE (2852 2300);
FORCEADD TAP..1
R 2
(-1375 975);
FORCEPROP 3 LASTPIN (-1325 975) SIG_NAME P5E_CPU0_PE1_TX_DN<4>
J 0
(-1315 985);
DISPLAY 0.659574 (-1315 985);
PAINT MONO (-1315 985);
DISPLAY INVISIBLE (-1315 985);
FORCEPROP 1 LASTPIN (-1325 975) BN 4
J 2
(-1313 983);
DISPLAY 0.680851 (-1313 983);
PAINT GREEN (-1313 983);
FORCEPROP 2 LAST CDS_LIB standard
J 0
(-1375 975);
DISPLAY INVISIBLE (-1375 975);
FORCEPROP 1 LAST BODY_TYPE PLUMBING
J 2
(-1375 1025);
DISPLAY 0.872340 (-1375 1025);
PAINT GREEN (-1375 1025);
DISPLAY INVISIBLE (-1375 1025);
FORCEPROP 1 LAST HDL_TAP TRUE
J 2
(-1700 850);
DISPLAY 0.872340 (-1700 850);
DISPLAY INVISIBLE (-1700 850);
FORCEPROP 1 LAST PATH I14
J 2
(-1373 975);
DISPLAY 0.872340 (-1373 975);
PAINT GREEN (-1373 975);
DISPLAY INVISIBLE (-1373 975);
FORCEADD TAP..1
R 2
(2850 2500);
FORCEPROP 3 LASTPIN (2900 2500) SIG_NAME P5E_CPU0_PE3_TX_DP<10>
J 0
(2910 2510);
DISPLAY 0.659574 (2910 2510);
PAINT MONO (2910 2510);
DISPLAY INVISIBLE (2910 2510);
FORCEPROP 1 LASTPIN (2900 2500) BN 10
J 2
(2912 2508);
DISPLAY 0.680851 (2912 2508);
PAINT GREEN (2912 2508);
FORCEPROP 2 LAST CDS_LIB standard
J 0
(2850 2500);
DISPLAY INVISIBLE (2850 2500);
FORCEPROP 1 LAST BODY_TYPE PLUMBING
J 2
(2850 2550);
DISPLAY 0.872340 (2850 2550);
PAINT GREEN (2850 2550);
DISPLAY INVISIBLE (2850 2550);
FORCEPROP 1 LAST HDL_TAP TRUE
J 2
(2525 2375);
DISPLAY 0.872340 (2525 2375);
DISPLAY INVISIBLE (2525 2375);
FORCEPROP 1 LAST PATH I140
J 2
(2852 2500);
DISPLAY 0.872340 (2852 2500);
PAINT GREEN (2852 2500);
DISPLAY INVISIBLE (2852 2500);
FORCEADD TAP..1
R 2
(2850 2700);
FORCEPROP 3 LASTPIN (2900 2700) SIG_NAME P5E_CPU0_PE3_TX_DP<11>
J 0
(2910 2710);
DISPLAY 0.659574 (2910 2710);
PAINT MONO (2910 2710);
DISPLAY INVISIBLE (2910 2710);
FORCEPROP 1 LASTPIN (2900 2700) BN 11
J 2
(2912 2708);
DISPLAY 0.680851 (2912 2708);
PAINT GREEN (2912 2708);
FORCEPROP 2 LAST CDS_LIB standard
J 0
(2850 2700);
DISPLAY INVISIBLE (2850 2700);
FORCEPROP 1 LAST BODY_TYPE PLUMBING
J 2
(2850 2750);
DISPLAY 0.872340 (2850 2750);
PAINT GREEN (2850 2750);
DISPLAY INVISIBLE (2850 2750);
FORCEPROP 1 LAST HDL_TAP TRUE
J 2
(2525 2575);
DISPLAY 0.872340 (2525 2575);
DISPLAY INVISIBLE (2525 2575);
FORCEPROP 1 LAST PATH I141
J 2
(2852 2700);
DISPLAY 0.872340 (2852 2700);
PAINT GREEN (2852 2700);
DISPLAY INVISIBLE (2852 2700);
FORCEADD TAP..1
R 2
(2850 2900);
FORCEPROP 3 LASTPIN (2900 2900) SIG_NAME P5E_CPU0_PE3_TX_DP<12>
J 0
(2910 2910);
DISPLAY 0.659574 (2910 2910);
PAINT MONO (2910 2910);
DISPLAY INVISIBLE (2910 2910);
FORCEPROP 1 LASTPIN (2900 2900) BN 12
J 2
(2912 2908);
DISPLAY 0.680851 (2912 2908);
PAINT GREEN (2912 2908);
FORCEPROP 2 LAST CDS_LIB standard
J 0
(2850 2900);
DISPLAY INVISIBLE (2850 2900);
FORCEPROP 1 LAST BODY_TYPE PLUMBING
J 2
(2850 2950);
DISPLAY 0.872340 (2850 2950);
PAINT GREEN (2850 2950);
DISPLAY INVISIBLE (2850 2950);
FORCEPROP 1 LAST HDL_TAP TRUE
J 2
(2525 2775);
DISPLAY 0.872340 (2525 2775);
DISPLAY INVISIBLE (2525 2775);
FORCEPROP 1 LAST PATH I142
J 2
(2852 2900);
DISPLAY 0.872340 (2852 2900);
PAINT GREEN (2852 2900);
DISPLAY INVISIBLE (2852 2900);
FORCEADD TAP..1
R 2
(2850 3100);
FORCEPROP 3 LASTPIN (2900 3100) SIG_NAME P5E_CPU0_PE3_TX_DP<13>
J 0
(2910 3110);
DISPLAY 0.659574 (2910 3110);
PAINT MONO (2910 3110);
DISPLAY INVISIBLE (2910 3110);
FORCEPROP 1 LASTPIN (2900 3100) BN 13
J 2
(2912 3108);
DISPLAY 0.680851 (2912 3108);
PAINT GREEN (2912 3108);
FORCEPROP 2 LAST CDS_LIB standard
J 0
(2850 3100);
DISPLAY INVISIBLE (2850 3100);
FORCEPROP 1 LAST BODY_TYPE PLUMBING
J 2
(2850 3150);
DISPLAY 0.872340 (2850 3150);
PAINT GREEN (2850 3150);
DISPLAY INVISIBLE (2850 3150);
FORCEPROP 1 LAST HDL_TAP TRUE
J 2
(2525 2975);
DISPLAY 0.872340 (2525 2975);
DISPLAY INVISIBLE (2525 2975);
FORCEPROP 1 LAST PATH I143
J 2
(2852 3100);
DISPLAY 0.872340 (2852 3100);
PAINT GREEN (2852 3100);
DISPLAY INVISIBLE (2852 3100);
FORCEADD TAP..1
R 2
(2850 3300);
FORCEPROP 3 LASTPIN (2900 3300) SIG_NAME P5E_CPU0_PE3_TX_DP<14>
J 0
(2910 3310);
DISPLAY 0.659574 (2910 3310);
PAINT MONO (2910 3310);
DISPLAY INVISIBLE (2910 3310);
FORCEPROP 1 LASTPIN (2900 3300) BN 14
J 2
(2912 3308);
DISPLAY 0.680851 (2912 3308);
PAINT GREEN (2912 3308);
FORCEPROP 2 LAST CDS_LIB standard
J 0
(2850 3300);
DISPLAY INVISIBLE (2850 3300);
FORCEPROP 1 LAST BODY_TYPE PLUMBING
J 2
(2850 3350);
DISPLAY 0.872340 (2850 3350);
PAINT GREEN (2850 3350);
DISPLAY INVISIBLE (2850 3350);
FORCEPROP 1 LAST HDL_TAP TRUE
J 2
(2525 3175);
DISPLAY 0.872340 (2525 3175);
DISPLAY INVISIBLE (2525 3175);
FORCEPROP 1 LAST PATH I144
J 2
(2852 3300);
DISPLAY 0.872340 (2852 3300);
PAINT GREEN (2852 3300);
DISPLAY INVISIBLE (2852 3300);
FORCEADD TAP..1
R 2
(2850 3500);
FORCEPROP 3 LASTPIN (2900 3500) SIG_NAME P5E_CPU0_PE3_TX_DP<15>
J 0
(2910 3510);
DISPLAY 0.659574 (2910 3510);
PAINT MONO (2910 3510);
DISPLAY INVISIBLE (2910 3510);
FORCEPROP 1 LASTPIN (2900 3500) BN 15
J 2
(2912 3508);
DISPLAY 0.680851 (2912 3508);
PAINT GREEN (2912 3508);
FORCEPROP 2 LAST CDS_LIB standard
J 0
(2850 3500);
DISPLAY INVISIBLE (2850 3500);
FORCEPROP 1 LAST BODY_TYPE PLUMBING
J 2
(2850 3550);
DISPLAY 0.872340 (2850 3550);
PAINT GREEN (2850 3550);
DISPLAY INVISIBLE (2850 3550);
FORCEPROP 1 LAST HDL_TAP TRUE
J 2
(2525 3375);
DISPLAY 0.872340 (2525 3375);
DISPLAY INVISIBLE (2525 3375);
FORCEPROP 1 LAST PATH I145
J 2
(2852 3500);
DISPLAY 0.872340 (2852 3500);
PAINT GREEN (2852 3500);
DISPLAY INVISIBLE (2852 3500);
FORCEADD TAP..1
R 2
(3100 2150);
FORCEPROP 3 LASTPIN (3150 2150) SIG_NAME P5E_CPU0_PE3_TX_DN<8>
J 0
(3160 2160);
DISPLAY 0.659574 (3160 2160);
PAINT MONO (3160 2160);
DISPLAY INVISIBLE (3160 2160);
FORCEPROP 1 LASTPIN (3150 2150) BN 8
J 2
(3162 2158);
DISPLAY 0.680851 (3162 2158);
PAINT GREEN (3162 2158);
FORCEPROP 2 LAST CDS_LIB standard
J 0
(3100 2150);
DISPLAY INVISIBLE (3100 2150);
FORCEPROP 1 LAST BODY_TYPE PLUMBING
J 2
(3100 2200);
DISPLAY 0.872340 (3100 2200);
PAINT GREEN (3100 2200);
DISPLAY INVISIBLE (3100 2200);
FORCEPROP 1 LAST HDL_TAP TRUE
J 2
(2775 2025);
DISPLAY 0.872340 (2775 2025);
DISPLAY INVISIBLE (2775 2025);
FORCEPROP 1 LAST PATH I146
J 2
(3102 2150);
DISPLAY 0.872340 (3102 2150);
PAINT GREEN (3102 2150);
DISPLAY INVISIBLE (3102 2150);
FORCEADD TAP..1
R 2
(3100 2350);
FORCEPROP 3 LASTPIN (3150 2350) SIG_NAME P5E_CPU0_PE3_TX_DN<9>
J 0
(3160 2360);
DISPLAY 0.659574 (3160 2360);
PAINT MONO (3160 2360);
DISPLAY INVISIBLE (3160 2360);
FORCEPROP 1 LASTPIN (3150 2350) BN 9
J 2
(3162 2358);
DISPLAY 0.680851 (3162 2358);
PAINT GREEN (3162 2358);
FORCEPROP 2 LAST CDS_LIB standard
J 0
(3100 2350);
DISPLAY INVISIBLE (3100 2350);
FORCEPROP 1 LAST BODY_TYPE PLUMBING
J 2
(3100 2400);
DISPLAY 0.872340 (3100 2400);
PAINT GREEN (3100 2400);
DISPLAY INVISIBLE (3100 2400);
FORCEPROP 1 LAST HDL_TAP TRUE
J 2
(2775 2225);
DISPLAY 0.872340 (2775 2225);
DISPLAY INVISIBLE (2775 2225);
FORCEPROP 1 LAST PATH I147
J 2
(3102 2350);
DISPLAY 0.872340 (3102 2350);
PAINT GREEN (3102 2350);
DISPLAY INVISIBLE (3102 2350);
FORCEADD TAP..1
R 2
(3100 2550);
FORCEPROP 3 LASTPIN (3150 2550) SIG_NAME P5E_CPU0_PE3_TX_DN<10>
J 0
(3160 2560);
DISPLAY 0.659574 (3160 2560);
PAINT MONO (3160 2560);
DISPLAY INVISIBLE (3160 2560);
FORCEPROP 1 LASTPIN (3150 2550) BN 10
J 2
(3162 2558);
DISPLAY 0.680851 (3162 2558);
PAINT GREEN (3162 2558);
FORCEPROP 2 LAST CDS_LIB standard
J 0
(3100 2550);
DISPLAY INVISIBLE (3100 2550);
FORCEPROP 1 LAST BODY_TYPE PLUMBING
J 2
(3100 2600);
DISPLAY 0.872340 (3100 2600);
PAINT GREEN (3100 2600);
DISPLAY INVISIBLE (3100 2600);
FORCEPROP 1 LAST HDL_TAP TRUE
J 2
(2775 2425);
DISPLAY 0.872340 (2775 2425);
DISPLAY INVISIBLE (2775 2425);
FORCEPROP 1 LAST PATH I148
J 2
(3102 2550);
DISPLAY 0.872340 (3102 2550);
PAINT GREEN (3102 2550);
DISPLAY INVISIBLE (3102 2550);
FORCEADD TAP..1
R 2
(3100 2750);
FORCEPROP 3 LASTPIN (3150 2750) SIG_NAME P5E_CPU0_PE3_TX_DN<11>
J 0
(3160 2760);
DISPLAY 0.659574 (3160 2760);
PAINT MONO (3160 2760);
DISPLAY INVISIBLE (3160 2760);
FORCEPROP 1 LASTPIN (3150 2750) BN 11
J 2
(3162 2758);
DISPLAY 0.680851 (3162 2758);
PAINT GREEN (3162 2758);
FORCEPROP 2 LAST CDS_LIB standard
J 0
(3100 2750);
DISPLAY INVISIBLE (3100 2750);
FORCEPROP 1 LAST BODY_TYPE PLUMBING
J 2
(3100 2800);
DISPLAY 0.872340 (3100 2800);
PAINT GREEN (3100 2800);
DISPLAY INVISIBLE (3100 2800);
FORCEPROP 1 LAST HDL_TAP TRUE
J 2
(2775 2625);
DISPLAY 0.872340 (2775 2625);
DISPLAY INVISIBLE (2775 2625);
FORCEPROP 1 LAST PATH I149
J 2
(3102 2750);
DISPLAY 0.872340 (3102 2750);
PAINT GREEN (3102 2750);
DISPLAY INVISIBLE (3102 2750);
FORCEADD TAP..1
R 2
(-1625 1125);
FORCEPROP 3 LASTPIN (-1575 1125) SIG_NAME P5E_CPU0_PE1_TX_DP<5>
J 0
(-1565 1135);
DISPLAY 0.659574 (-1565 1135);
PAINT MONO (-1565 1135);
DISPLAY INVISIBLE (-1565 1135);
FORCEPROP 1 LASTPIN (-1575 1125) BN 5
J 2
(-1563 1133);
DISPLAY 0.680851 (-1563 1133);
PAINT GREEN (-1563 1133);
FORCEPROP 2 LAST CDS_LIB standard
J 0
(-1625 1125);
DISPLAY INVISIBLE (-1625 1125);
FORCEPROP 1 LAST BODY_TYPE PLUMBING
J 2
(-1625 1175);
DISPLAY 0.872340 (-1625 1175);
PAINT GREEN (-1625 1175);
DISPLAY INVISIBLE (-1625 1175);
FORCEPROP 1 LAST HDL_TAP TRUE
J 2
(-1950 1000);
DISPLAY 0.872340 (-1950 1000);
DISPLAY INVISIBLE (-1950 1000);
FORCEPROP 1 LAST PATH I15
J 2
(-1623 1125);
DISPLAY 0.872340 (-1623 1125);
PAINT GREEN (-1623 1125);
DISPLAY INVISIBLE (-1623 1125);
FORCEADD TAP..1
R 2
(3100 2950);
FORCEPROP 3 LASTPIN (3150 2950) SIG_NAME P5E_CPU0_PE3_TX_DN<12>
J 0
(3160 2960);
DISPLAY 0.659574 (3160 2960);
PAINT MONO (3160 2960);
DISPLAY INVISIBLE (3160 2960);
FORCEPROP 1 LASTPIN (3150 2950) BN 12
J 2
(3162 2958);
DISPLAY 0.680851 (3162 2958);
PAINT GREEN (3162 2958);
FORCEPROP 2 LAST CDS_LIB standard
J 0
(3100 2950);
DISPLAY INVISIBLE (3100 2950);
FORCEPROP 1 LAST BODY_TYPE PLUMBING
J 2
(3100 3000);
DISPLAY 0.872340 (3100 3000);
PAINT GREEN (3100 3000);
DISPLAY INVISIBLE (3100 3000);
FORCEPROP 1 LAST HDL_TAP TRUE
J 2
(2775 2825);
DISPLAY 0.872340 (2775 2825);
DISPLAY INVISIBLE (2775 2825);
FORCEPROP 1 LAST PATH I150
J 2
(3102 2950);
DISPLAY 0.872340 (3102 2950);
PAINT GREEN (3102 2950);
DISPLAY INVISIBLE (3102 2950);
FORCEADD Q_CAP_DIFFBUS..2
R 2
(3825 2150);
FORCEPROP 1 LAST PART_NUMBER SP_CH4221MEE01
J 2
(3709 2238);
DISPLAY 0.574468 (3709 2238);
PAINT GREEN (3709 2238);
DISPLAY INVISIBLE (3709 2238);
FORCEPROP 2 LAST VALUE DIFF BUS_0.22UF
J 2
(3675 2150);
DISPLAY 0.553191 (3675 2150);
FORCEPROP 1 LAST $LOCATION C884
J 2
(4059 2167);
DISPLAY 0.723404 (4059 2167);
PAINT GREEN (4059 2167);
FORCEPROP 2 LASTPIN (3900 2150) $PN 1
J 0
(3910 2160);
DISPLAY 0.808511 (3910 2160);
FORCEPROP 2 LASTPIN (3750 2150) $PN 2
J 2
(3740 2160);
DISPLAY 0.808511 (3740 2160);
FORCEPROP 1 LAST CDS_LMAN_SYM_OUTLINE -25,50,25,-50
J 2
(3825 2150);
DISPLAY 0.468085 (3825 2150);
PAINT GREEN (3825 2150);
DISPLAY INVISIBLE (3825 2150);
FORCEPROP 2 LAST CDS_LIB pure_quanta
J 2
(3825 2150);
DISPLAY INVISIBLE (3825 2150);
FORCEPROP 1 LAST PIN_NAMES_ROTATE TRUE
J 2
(3825 2150);
DISPLAY 0.489362 (3825 2150);
PAINT GREEN (3825 2150);
DISPLAY INVISIBLE (3825 2150);
FORCEPROP 2 LAST VOLTAGE 6.3V
J 2
(3475 2200);
DISPLAY 0.553191 (3475 2200);
DISPLAY INVISIBLE (3475 2200);
FORCEPROP 1 LAST MATERIAL X6S
J 2
(3834 2229);
DISPLAY 0.574468 (3834 2229);
PAINT GREEN (3834 2229);
DISPLAY INVISIBLE (3834 2229);
FORCEPROP 2 LAST PACK_TYPE C0201
J 2
(3650 2200);
DISPLAY 0.553191 (3650 2200);
DISPLAY INVISIBLE (3650 2200);
FORCEPROP 2 LAST TOLERANCE 20%
J 2
(3750 2200);
DISPLAY 0.553191 (3750 2200);
DISPLAY INVISIBLE (3750 2200);
FORCEPROP 1 LAST PATH I151
J 2
(3825 2150);
DISPLAY 0.723404 (3825 2150);
DISPLAY INVISIBLE (3825 2150);
FORCEPROP 1 LAST $LOCATION C884
J 0
(4075 2225);
DISPLAY 1.021277 (4075 2225);
DISPLAY INVISIBLE (4075 2225);
FORCEPROP 2 LAST CDS_LOCATION C884
J 0
(4075 2225);
DISPLAY 1.021277 (4075 2225);
DISPLAY INVISIBLE (4075 2225);
FORCEPROP 2 LAST $SEC 1
J 2
(4000 2225);
DISPLAY 0.680851 (4000 2225);
PAINT MONO (4000 2225);
DISPLAY INVISIBLE (4000 2225);
FORCEPROP 2 LAST CDS_SEC 1
J 2
(4000 2225);
DISPLAY 0.680851 (4000 2225);
DISPLAY INVISIBLE (4000 2225);
FORCEADD Q_CAP_DIFFBUS..2
R 2
(3825 2100);
FORCEPROP 1 LAST PART_NUMBER SP_CH4221MEE01
J 2
(3709 2188);
DISPLAY 0.574468 (3709 2188);
PAINT GREEN (3709 2188);
DISPLAY INVISIBLE (3709 2188);
FORCEPROP 2 LAST VALUE DIFF BUS_0.22UF
J 2
(3675 2100);
DISPLAY 0.553191 (3675 2100);
FORCEPROP 1 LAST $LOCATION C885
J 2
(4059 2117);
DISPLAY 0.723404 (4059 2117);
PAINT GREEN (4059 2117);
FORCEPROP 2 LASTPIN (3900 2100) $PN 1
J 0
(3910 2110);
DISPLAY 0.808511 (3910 2110);
FORCEPROP 2 LASTPIN (3750 2100) $PN 2
J 2
(3740 2110);
DISPLAY 0.808511 (3740 2110);
FORCEPROP 1 LAST CDS_LMAN_SYM_OUTLINE -25,50,25,-50
J 2
(3825 2100);
DISPLAY 0.468085 (3825 2100);
PAINT GREEN (3825 2100);
DISPLAY INVISIBLE (3825 2100);
FORCEPROP 2 LAST CDS_LIB pure_quanta
J 2
(3825 2100);
DISPLAY INVISIBLE (3825 2100);
FORCEPROP 1 LAST PIN_NAMES_ROTATE TRUE
J 2
(3825 2100);
DISPLAY 0.489362 (3825 2100);
PAINT GREEN (3825 2100);
DISPLAY INVISIBLE (3825 2100);
FORCEPROP 2 LAST VOLTAGE 6.3V
J 2
(3475 2150);
DISPLAY 0.553191 (3475 2150);
DISPLAY INVISIBLE (3475 2150);
FORCEPROP 1 LAST MATERIAL X6S
J 2
(3834 2179);
DISPLAY 0.574468 (3834 2179);
PAINT GREEN (3834 2179);
DISPLAY INVISIBLE (3834 2179);
FORCEPROP 2 LAST PACK_TYPE C0201
J 2
(3650 2150);
DISPLAY 0.553191 (3650 2150);
DISPLAY INVISIBLE (3650 2150);
FORCEPROP 2 LAST TOLERANCE 20%
J 2
(3750 2150);
DISPLAY 0.553191 (3750 2150);
DISPLAY INVISIBLE (3750 2150);
FORCEPROP 1 LAST PATH I152
J 2
(3825 2100);
DISPLAY 0.723404 (3825 2100);
DISPLAY INVISIBLE (3825 2100);
FORCEPROP 1 LAST $LOCATION C885
J 0
(4075 2175);
DISPLAY 1.021277 (4075 2175);
DISPLAY INVISIBLE (4075 2175);
FORCEPROP 2 LAST CDS_LOCATION C885
J 0
(4075 2175);
DISPLAY 1.021277 (4075 2175);
DISPLAY INVISIBLE (4075 2175);
FORCEPROP 2 LAST $SEC 1
J 2
(4000 2175);
DISPLAY 0.680851 (4000 2175);
PAINT MONO (4000 2175);
DISPLAY INVISIBLE (4000 2175);
FORCEPROP 2 LAST CDS_SEC 1
J 2
(4000 2175);
DISPLAY 0.680851 (4000 2175);
DISPLAY INVISIBLE (4000 2175);
FORCEADD Q_CAP_DIFFBUS..2
R 2
(3825 2300);
FORCEPROP 1 LAST PART_NUMBER SP_CH4221MEE01
J 2
(3709 2388);
DISPLAY 0.574468 (3709 2388);
PAINT GREEN (3709 2388);
DISPLAY INVISIBLE (3709 2388);
FORCEPROP 2 LAST VALUE DIFF BUS_0.22UF
J 2
(3675 2300);
DISPLAY 0.553191 (3675 2300);
FORCEPROP 1 LAST $LOCATION C883
J 2
(4059 2317);
DISPLAY 0.723404 (4059 2317);
PAINT GREEN (4059 2317);
FORCEPROP 2 LASTPIN (3900 2300) $PN 1
J 0
(3910 2310);
DISPLAY 0.808511 (3910 2310);
FORCEPROP 2 LASTPIN (3750 2300) $PN 2
J 2
(3740 2310);
DISPLAY 0.808511 (3740 2310);
FORCEPROP 1 LAST CDS_LMAN_SYM_OUTLINE -25,50,25,-50
J 2
(3825 2300);
DISPLAY 0.468085 (3825 2300);
PAINT GREEN (3825 2300);
DISPLAY INVISIBLE (3825 2300);
FORCEPROP 2 LAST CDS_LIB pure_quanta
J 2
(3825 2300);
DISPLAY INVISIBLE (3825 2300);
FORCEPROP 1 LAST PIN_NAMES_ROTATE TRUE
J 2
(3825 2300);
DISPLAY 0.489362 (3825 2300);
PAINT GREEN (3825 2300);
DISPLAY INVISIBLE (3825 2300);
FORCEPROP 2 LAST VOLTAGE 6.3V
J 2
(3475 2350);
DISPLAY 0.553191 (3475 2350);
DISPLAY INVISIBLE (3475 2350);
FORCEPROP 1 LAST MATERIAL X6S
J 2
(3834 2379);
DISPLAY 0.574468 (3834 2379);
PAINT GREEN (3834 2379);
DISPLAY INVISIBLE (3834 2379);
FORCEPROP 2 LAST PACK_TYPE C0201
J 2
(3650 2350);
DISPLAY 0.553191 (3650 2350);
DISPLAY INVISIBLE (3650 2350);
FORCEPROP 2 LAST TOLERANCE 20%
J 2
(3750 2350);
DISPLAY 0.553191 (3750 2350);
DISPLAY INVISIBLE (3750 2350);
FORCEPROP 1 LAST PATH I153
J 2
(3825 2300);
DISPLAY 0.723404 (3825 2300);
DISPLAY INVISIBLE (3825 2300);
FORCEPROP 1 LAST $LOCATION C883
J 0
(4075 2375);
DISPLAY 1.021277 (4075 2375);
DISPLAY INVISIBLE (4075 2375);
FORCEPROP 2 LAST CDS_LOCATION C883
J 0
(4075 2375);
DISPLAY 1.021277 (4075 2375);
DISPLAY INVISIBLE (4075 2375);
FORCEPROP 2 LAST $SEC 1
J 2
(4000 2375);
DISPLAY 0.680851 (4000 2375);
PAINT MONO (4000 2375);
DISPLAY INVISIBLE (4000 2375);
FORCEPROP 2 LAST CDS_SEC 1
J 2
(4000 2375);
DISPLAY 0.680851 (4000 2375);
DISPLAY INVISIBLE (4000 2375);
FORCEADD Q_CAP_DIFFBUS..2
R 2
(3825 2350);
FORCEPROP 1 LAST PART_NUMBER SP_CH4221MEE01
J 2
(3709 2438);
DISPLAY 0.574468 (3709 2438);
PAINT GREEN (3709 2438);
DISPLAY INVISIBLE (3709 2438);
FORCEPROP 2 LAST VALUE DIFF BUS_0.22UF
J 2
(3675 2350);
DISPLAY 0.553191 (3675 2350);
FORCEPROP 1 LAST $LOCATION C882
J 2
(4059 2367);
DISPLAY 0.723404 (4059 2367);
PAINT GREEN (4059 2367);
FORCEPROP 2 LASTPIN (3900 2350) $PN 1
J 0
(3910 2360);
DISPLAY 0.808511 (3910 2360);
FORCEPROP 2 LASTPIN (3750 2350) $PN 2
J 2
(3740 2360);
DISPLAY 0.808511 (3740 2360);
FORCEPROP 2 LAST CDS_LIB pure_quanta
J 2
(3825 2350);
DISPLAY INVISIBLE (3825 2350);
FORCEPROP 1 LAST CDS_LMAN_SYM_OUTLINE -25,50,25,-50
J 2
(3825 2350);
DISPLAY 0.468085 (3825 2350);
PAINT GREEN (3825 2350);
DISPLAY INVISIBLE (3825 2350);
FORCEPROP 1 LAST PIN_NAMES_ROTATE TRUE
J 2
(3825 2350);
DISPLAY 0.489362 (3825 2350);
PAINT GREEN (3825 2350);
DISPLAY INVISIBLE (3825 2350);
FORCEPROP 2 LAST VOLTAGE 6.3V
J 2
(3475 2400);
DISPLAY 0.553191 (3475 2400);
DISPLAY INVISIBLE (3475 2400);
FORCEPROP 1 LAST MATERIAL X6S
J 2
(3834 2429);
DISPLAY 0.574468 (3834 2429);
PAINT GREEN (3834 2429);
DISPLAY INVISIBLE (3834 2429);
FORCEPROP 2 LAST PACK_TYPE C0201
J 2
(3650 2400);
DISPLAY 0.553191 (3650 2400);
DISPLAY INVISIBLE (3650 2400);
FORCEPROP 2 LAST TOLERANCE 20%
J 2
(3750 2400);
DISPLAY 0.553191 (3750 2400);
DISPLAY INVISIBLE (3750 2400);
FORCEPROP 1 LAST PATH I154
J 2
(3825 2350);
DISPLAY 0.723404 (3825 2350);
DISPLAY INVISIBLE (3825 2350);
FORCEPROP 1 LAST $LOCATION C882
J 0
(4075 2425);
DISPLAY 1.021277 (4075 2425);
DISPLAY INVISIBLE (4075 2425);
FORCEPROP 2 LAST CDS_LOCATION C882
J 0
(4075 2425);
DISPLAY 1.021277 (4075 2425);
DISPLAY INVISIBLE (4075 2425);
FORCEPROP 2 LAST $SEC 1
J 2
(4000 2425);
DISPLAY 0.680851 (4000 2425);
PAINT MONO (4000 2425);
DISPLAY INVISIBLE (4000 2425);
FORCEPROP 2 LAST CDS_SEC 1
J 2
(4000 2425);
DISPLAY 0.680851 (4000 2425);
DISPLAY INVISIBLE (4000 2425);
FORCEADD Q_CAP_DIFFBUS..2
R 2
(3825 2500);
FORCEPROP 1 LAST PART_NUMBER SP_CH4221MEE01
J 2
(3709 2588);
DISPLAY 0.574468 (3709 2588);
PAINT GREEN (3709 2588);
DISPLAY INVISIBLE (3709 2588);
FORCEPROP 2 LAST VALUE DIFF BUS_0.22UF
J 2
(3675 2500);
DISPLAY 0.553191 (3675 2500);
FORCEPROP 1 LAST $LOCATION C881
J 2
(4059 2517);
DISPLAY 0.723404 (4059 2517);
PAINT GREEN (4059 2517);
FORCEPROP 2 LASTPIN (3900 2500) $PN 1
J 0
(3910 2510);
DISPLAY 0.808511 (3910 2510);
FORCEPROP 2 LASTPIN (3750 2500) $PN 2
J 2
(3740 2510);
DISPLAY 0.808511 (3740 2510);
FORCEPROP 1 LAST CDS_LMAN_SYM_OUTLINE -25,50,25,-50
J 2
(3825 2500);
DISPLAY 0.468085 (3825 2500);
PAINT GREEN (3825 2500);
DISPLAY INVISIBLE (3825 2500);
FORCEPROP 2 LAST CDS_LIB pure_quanta
J 2
(3825 2500);
DISPLAY INVISIBLE (3825 2500);
FORCEPROP 1 LAST PIN_NAMES_ROTATE TRUE
J 2
(3825 2500);
DISPLAY 0.489362 (3825 2500);
PAINT GREEN (3825 2500);
DISPLAY INVISIBLE (3825 2500);
FORCEPROP 2 LAST VOLTAGE 6.3V
J 2
(3475 2550);
DISPLAY 0.553191 (3475 2550);
DISPLAY INVISIBLE (3475 2550);
FORCEPROP 1 LAST MATERIAL X6S
J 2
(3834 2579);
DISPLAY 0.574468 (3834 2579);
PAINT GREEN (3834 2579);
DISPLAY INVISIBLE (3834 2579);
FORCEPROP 2 LAST PACK_TYPE C0201
J 2
(3650 2550);
DISPLAY 0.553191 (3650 2550);
DISPLAY INVISIBLE (3650 2550);
FORCEPROP 2 LAST TOLERANCE 20%
J 2
(3750 2550);
DISPLAY 0.553191 (3750 2550);
DISPLAY INVISIBLE (3750 2550);
FORCEPROP 1 LAST PATH I155
J 2
(3825 2500);
DISPLAY 0.723404 (3825 2500);
DISPLAY INVISIBLE (3825 2500);
FORCEPROP 1 LAST $LOCATION C881
J 0
(4075 2575);
DISPLAY 1.021277 (4075 2575);
DISPLAY INVISIBLE (4075 2575);
FORCEPROP 2 LAST CDS_LOCATION C881
J 0
(4075 2575);
DISPLAY 1.021277 (4075 2575);
DISPLAY INVISIBLE (4075 2575);
FORCEPROP 2 LAST $SEC 1
J 2
(4000 2575);
DISPLAY 0.680851 (4000 2575);
PAINT MONO (4000 2575);
DISPLAY INVISIBLE (4000 2575);
FORCEPROP 2 LAST CDS_SEC 1
J 2
(4000 2575);
DISPLAY 0.680851 (4000 2575);
DISPLAY INVISIBLE (4000 2575);
FORCEADD Q_CAP_DIFFBUS..2
R 2
(3825 2550);
FORCEPROP 1 LAST PART_NUMBER SP_CH4221MEE01
J 2
(3709 2638);
DISPLAY 0.574468 (3709 2638);
PAINT GREEN (3709 2638);
DISPLAY INVISIBLE (3709 2638);
FORCEPROP 2 LAST VALUE DIFF BUS_0.22UF
J 2
(3675 2550);
DISPLAY 0.553191 (3675 2550);
FORCEPROP 1 LAST $LOCATION C880
J 2
(4059 2567);
DISPLAY 0.723404 (4059 2567);
PAINT GREEN (4059 2567);
FORCEPROP 2 LASTPIN (3900 2550) $PN 1
J 0
(3910 2560);
DISPLAY 0.808511 (3910 2560);
FORCEPROP 2 LASTPIN (3750 2550) $PN 2
J 2
(3740 2560);
DISPLAY 0.808511 (3740 2560);
FORCEPROP 1 LAST CDS_LMAN_SYM_OUTLINE -25,50,25,-50
J 2
(3825 2550);
DISPLAY 0.468085 (3825 2550);
PAINT GREEN (3825 2550);
DISPLAY INVISIBLE (3825 2550);
FORCEPROP 2 LAST CDS_LIB pure_quanta
J 2
(3825 2550);
DISPLAY INVISIBLE (3825 2550);
FORCEPROP 1 LAST PIN_NAMES_ROTATE TRUE
J 2
(3825 2550);
DISPLAY 0.489362 (3825 2550);
PAINT GREEN (3825 2550);
DISPLAY INVISIBLE (3825 2550);
FORCEPROP 2 LAST VOLTAGE 6.3V
J 2
(3475 2600);
DISPLAY 0.553191 (3475 2600);
DISPLAY INVISIBLE (3475 2600);
FORCEPROP 1 LAST MATERIAL X6S
J 2
(3834 2629);
DISPLAY 0.574468 (3834 2629);
PAINT GREEN (3834 2629);
DISPLAY INVISIBLE (3834 2629);
FORCEPROP 2 LAST PACK_TYPE C0201
J 2
(3650 2600);
DISPLAY 0.553191 (3650 2600);
DISPLAY INVISIBLE (3650 2600);
FORCEPROP 2 LAST TOLERANCE 20%
J 2
(3750 2600);
DISPLAY 0.553191 (3750 2600);
DISPLAY INVISIBLE (3750 2600);
FORCEPROP 1 LAST PATH I156
J 2
(3825 2550);
DISPLAY 0.723404 (3825 2550);
DISPLAY INVISIBLE (3825 2550);
FORCEPROP 1 LAST $LOCATION C880
J 0
(4075 2625);
DISPLAY 1.021277 (4075 2625);
DISPLAY INVISIBLE (4075 2625);
FORCEPROP 2 LAST CDS_LOCATION C880
J 0
(4075 2625);
DISPLAY 1.021277 (4075 2625);
DISPLAY INVISIBLE (4075 2625);
FORCEPROP 2 LAST $SEC 1
J 2
(4000 2625);
DISPLAY 0.680851 (4000 2625);
PAINT MONO (4000 2625);
DISPLAY INVISIBLE (4000 2625);
FORCEPROP 2 LAST CDS_SEC 1
J 2
(4000 2625);
DISPLAY 0.680851 (4000 2625);
DISPLAY INVISIBLE (4000 2625);
FORCEADD Q_CAP_DIFFBUS..2
R 2
(3825 2750);
FORCEPROP 1 LAST PART_NUMBER SP_CH4221MEE01
J 2
(3709 2838);
DISPLAY 0.574468 (3709 2838);
PAINT GREEN (3709 2838);
DISPLAY INVISIBLE (3709 2838);
FORCEPROP 2 LAST VALUE DIFF BUS_0.22UF
J 2
(3675 2750);
DISPLAY 0.553191 (3675 2750);
FORCEPROP 1 LAST $LOCATION C878
J 2
(4059 2767);
DISPLAY 0.723404 (4059 2767);
PAINT GREEN (4059 2767);
FORCEPROP 2 LASTPIN (3900 2750) $PN 1
J 0
(3910 2760);
DISPLAY 0.808511 (3910 2760);
FORCEPROP 2 LASTPIN (3750 2750) $PN 2
J 2
(3740 2760);
DISPLAY 0.808511 (3740 2760);
FORCEPROP 2 LAST CDS_LIB pure_quanta
J 2
(3825 2750);
DISPLAY INVISIBLE (3825 2750);
FORCEPROP 1 LAST CDS_LMAN_SYM_OUTLINE -25,50,25,-50
J 2
(3825 2750);
DISPLAY 0.468085 (3825 2750);
PAINT GREEN (3825 2750);
DISPLAY INVISIBLE (3825 2750);
FORCEPROP 1 LAST PIN_NAMES_ROTATE TRUE
J 2
(3825 2750);
DISPLAY 0.489362 (3825 2750);
PAINT GREEN (3825 2750);
DISPLAY INVISIBLE (3825 2750);
FORCEPROP 2 LAST VOLTAGE 6.3V
J 2
(3475 2800);
DISPLAY 0.553191 (3475 2800);
DISPLAY INVISIBLE (3475 2800);
FORCEPROP 1 LAST MATERIAL X6S
J 2
(3834 2829);
DISPLAY 0.574468 (3834 2829);
PAINT GREEN (3834 2829);
DISPLAY INVISIBLE (3834 2829);
FORCEPROP 2 LAST PACK_TYPE C0201
J 2
(3650 2800);
DISPLAY 0.553191 (3650 2800);
DISPLAY INVISIBLE (3650 2800);
FORCEPROP 2 LAST TOLERANCE 20%
J 2
(3750 2800);
DISPLAY 0.553191 (3750 2800);
DISPLAY INVISIBLE (3750 2800);
FORCEPROP 1 LAST PATH I157
J 2
(3825 2750);
DISPLAY 0.723404 (3825 2750);
DISPLAY INVISIBLE (3825 2750);
FORCEPROP 1 LAST $LOCATION C878
J 0
(4075 2825);
DISPLAY 1.021277 (4075 2825);
DISPLAY INVISIBLE (4075 2825);
FORCEPROP 2 LAST CDS_LOCATION C878
J 0
(4075 2825);
DISPLAY 1.021277 (4075 2825);
DISPLAY INVISIBLE (4075 2825);
FORCEPROP 2 LAST $SEC 1
J 2
(4000 2825);
DISPLAY 0.680851 (4000 2825);
PAINT MONO (4000 2825);
DISPLAY INVISIBLE (4000 2825);
FORCEPROP 2 LAST CDS_SEC 1
J 2
(4000 2825);
DISPLAY 0.680851 (4000 2825);
DISPLAY INVISIBLE (4000 2825);
FORCEADD Q_CAP_DIFFBUS..2
R 2
(3825 2700);
FORCEPROP 1 LAST PART_NUMBER SP_CH4221MEE01
J 2
(3709 2788);
DISPLAY 0.574468 (3709 2788);
PAINT GREEN (3709 2788);
DISPLAY INVISIBLE (3709 2788);
FORCEPROP 2 LAST VALUE DIFF BUS_0.22UF
J 2
(3675 2700);
DISPLAY 0.553191 (3675 2700);
FORCEPROP 1 LAST $LOCATION C879
J 2
(4059 2717);
DISPLAY 0.723404 (4059 2717);
PAINT GREEN (4059 2717);
FORCEPROP 2 LASTPIN (3900 2700) $PN 1
J 0
(3910 2710);
DISPLAY 0.808511 (3910 2710);
FORCEPROP 2 LASTPIN (3750 2700) $PN 2
J 2
(3740 2710);
DISPLAY 0.808511 (3740 2710);
FORCEPROP 2 LAST CDS_LIB pure_quanta
J 2
(3825 2700);
DISPLAY INVISIBLE (3825 2700);
FORCEPROP 1 LAST CDS_LMAN_SYM_OUTLINE -25,50,25,-50
J 2
(3825 2700);
DISPLAY 0.468085 (3825 2700);
PAINT GREEN (3825 2700);
DISPLAY INVISIBLE (3825 2700);
FORCEPROP 1 LAST PIN_NAMES_ROTATE TRUE
J 2
(3825 2700);
DISPLAY 0.489362 (3825 2700);
PAINT GREEN (3825 2700);
DISPLAY INVISIBLE (3825 2700);
FORCEPROP 2 LAST VOLTAGE 6.3V
J 2
(3475 2750);
DISPLAY 0.553191 (3475 2750);
DISPLAY INVISIBLE (3475 2750);
FORCEPROP 1 LAST MATERIAL X6S
J 2
(3834 2779);
DISPLAY 0.574468 (3834 2779);
PAINT GREEN (3834 2779);
DISPLAY INVISIBLE (3834 2779);
FORCEPROP 2 LAST PACK_TYPE C0201
J 2
(3650 2750);
DISPLAY 0.553191 (3650 2750);
DISPLAY INVISIBLE (3650 2750);
FORCEPROP 2 LAST TOLERANCE 20%
J 2
(3750 2750);
DISPLAY 0.553191 (3750 2750);
DISPLAY INVISIBLE (3750 2750);
FORCEPROP 1 LAST PATH I158
J 2
(3825 2700);
DISPLAY 0.723404 (3825 2700);
DISPLAY INVISIBLE (3825 2700);
FORCEPROP 1 LAST $LOCATION C879
J 0
(4075 2775);
DISPLAY 1.021277 (4075 2775);
DISPLAY INVISIBLE (4075 2775);
FORCEPROP 2 LAST CDS_LOCATION C879
J 0
(4075 2775);
DISPLAY 1.021277 (4075 2775);
DISPLAY INVISIBLE (4075 2775);
FORCEPROP 2 LAST $SEC 1
J 2
(4000 2775);
DISPLAY 0.680851 (4000 2775);
PAINT MONO (4000 2775);
DISPLAY INVISIBLE (4000 2775);
FORCEPROP 2 LAST CDS_SEC 1
J 2
(4000 2775);
DISPLAY 0.680851 (4000 2775);
DISPLAY INVISIBLE (4000 2775);
FORCEADD Q_CAP_DIFFBUS..2
R 2
(3825 2900);
FORCEPROP 1 LAST PART_NUMBER SP_CH4221MEE01
J 2
(3709 2988);
DISPLAY 0.574468 (3709 2988);
PAINT GREEN (3709 2988);
DISPLAY INVISIBLE (3709 2988);
FORCEPROP 2 LAST VALUE DIFF BUS_0.22UF
J 2
(3675 2900);
DISPLAY 0.553191 (3675 2900);
FORCEPROP 1 LAST $LOCATION C877
J 2
(4059 2917);
DISPLAY 0.723404 (4059 2917);
PAINT GREEN (4059 2917);
FORCEPROP 2 LASTPIN (3900 2900) $PN 1
J 0
(3910 2910);
DISPLAY 0.808511 (3910 2910);
FORCEPROP 2 LASTPIN (3750 2900) $PN 2
J 2
(3740 2910);
DISPLAY 0.808511 (3740 2910);
FORCEPROP 1 LAST CDS_LMAN_SYM_OUTLINE -25,50,25,-50
J 2
(3825 2900);
DISPLAY 0.468085 (3825 2900);
PAINT GREEN (3825 2900);
DISPLAY INVISIBLE (3825 2900);
FORCEPROP 2 LAST CDS_LIB pure_quanta
J 2
(3825 2900);
DISPLAY INVISIBLE (3825 2900);
FORCEPROP 1 LAST PIN_NAMES_ROTATE TRUE
J 2
(3825 2900);
DISPLAY 0.489362 (3825 2900);
PAINT GREEN (3825 2900);
DISPLAY INVISIBLE (3825 2900);
FORCEPROP 2 LAST VOLTAGE 6.3V
J 2
(3475 2950);
DISPLAY 0.553191 (3475 2950);
DISPLAY INVISIBLE (3475 2950);
FORCEPROP 1 LAST MATERIAL X6S
J 2
(3834 2979);
DISPLAY 0.574468 (3834 2979);
PAINT GREEN (3834 2979);
DISPLAY INVISIBLE (3834 2979);
FORCEPROP 2 LAST PACK_TYPE C0201
J 2
(3650 2950);
DISPLAY 0.553191 (3650 2950);
DISPLAY INVISIBLE (3650 2950);
FORCEPROP 2 LAST TOLERANCE 20%
J 2
(3750 2950);
DISPLAY 0.553191 (3750 2950);
DISPLAY INVISIBLE (3750 2950);
FORCEPROP 1 LAST PATH I159
J 2
(3825 2900);
DISPLAY 0.723404 (3825 2900);
DISPLAY INVISIBLE (3825 2900);
FORCEPROP 1 LAST $LOCATION C877
J 0
(4075 2975);
DISPLAY 1.021277 (4075 2975);
DISPLAY INVISIBLE (4075 2975);
FORCEPROP 2 LAST CDS_LOCATION C877
J 0
(4075 2975);
DISPLAY 1.021277 (4075 2975);
DISPLAY INVISIBLE (4075 2975);
FORCEPROP 2 LAST $SEC 1
J 2
(4000 2975);
DISPLAY 0.680851 (4000 2975);
PAINT MONO (4000 2975);
DISPLAY INVISIBLE (4000 2975);
FORCEPROP 2 LAST CDS_SEC 1
J 2
(4000 2975);
DISPLAY 0.680851 (4000 2975);
DISPLAY INVISIBLE (4000 2975);
FORCEADD TAP..1
R 2
(-1625 1325);
FORCEPROP 3 LASTPIN (-1575 1325) SIG_NAME P5E_CPU0_PE1_TX_DP<6>
J 0
(-1565 1335);
DISPLAY 0.659574 (-1565 1335);
PAINT MONO (-1565 1335);
DISPLAY INVISIBLE (-1565 1335);
FORCEPROP 1 LASTPIN (-1575 1325) BN 6
J 2
(-1563 1333);
DISPLAY 0.680851 (-1563 1333);
PAINT GREEN (-1563 1333);
FORCEPROP 2 LAST CDS_LIB standard
J 0
(-1625 1325);
DISPLAY INVISIBLE (-1625 1325);
FORCEPROP 1 LAST BODY_TYPE PLUMBING
J 2
(-1625 1375);
DISPLAY 0.872340 (-1625 1375);
PAINT GREEN (-1625 1375);
DISPLAY INVISIBLE (-1625 1375);
FORCEPROP 1 LAST HDL_TAP TRUE
J 2
(-1950 1200);
DISPLAY 0.872340 (-1950 1200);
DISPLAY INVISIBLE (-1950 1200);
FORCEPROP 1 LAST PATH I16
J 2
(-1623 1325);
DISPLAY 0.872340 (-1623 1325);
PAINT GREEN (-1623 1325);
DISPLAY INVISIBLE (-1623 1325);
FORCEADD Q_CAP_DIFFBUS..2
R 2
(3825 2950);
FORCEPROP 1 LAST PART_NUMBER SP_CH4221MEE01
J 2
(3709 3038);
DISPLAY 0.574468 (3709 3038);
PAINT GREEN (3709 3038);
DISPLAY INVISIBLE (3709 3038);
FORCEPROP 2 LAST VALUE DIFF BUS_0.22UF
J 2
(3675 2950);
DISPLAY 0.553191 (3675 2950);
FORCEPROP 1 LAST $LOCATION C876
J 2
(4059 2967);
DISPLAY 0.723404 (4059 2967);
PAINT GREEN (4059 2967);
FORCEPROP 2 LASTPIN (3900 2950) $PN 1
J 0
(3910 2960);
DISPLAY 0.808511 (3910 2960);
FORCEPROP 2 LASTPIN (3750 2950) $PN 2
J 2
(3740 2960);
DISPLAY 0.808511 (3740 2960);
FORCEPROP 1 LAST CDS_LMAN_SYM_OUTLINE -25,50,25,-50
J 2
(3825 2950);
DISPLAY 0.468085 (3825 2950);
PAINT GREEN (3825 2950);
DISPLAY INVISIBLE (3825 2950);
FORCEPROP 2 LAST CDS_LIB pure_quanta
J 2
(3825 2950);
DISPLAY INVISIBLE (3825 2950);
FORCEPROP 1 LAST PIN_NAMES_ROTATE TRUE
J 2
(3825 2950);
DISPLAY 0.489362 (3825 2950);
PAINT GREEN (3825 2950);
DISPLAY INVISIBLE (3825 2950);
FORCEPROP 2 LAST VOLTAGE 6.3V
J 2
(3475 3000);
DISPLAY 0.553191 (3475 3000);
DISPLAY INVISIBLE (3475 3000);
FORCEPROP 1 LAST MATERIAL X6S
J 2
(3834 3029);
DISPLAY 0.574468 (3834 3029);
PAINT GREEN (3834 3029);
DISPLAY INVISIBLE (3834 3029);
FORCEPROP 2 LAST PACK_TYPE C0201
J 2
(3650 3000);
DISPLAY 0.553191 (3650 3000);
DISPLAY INVISIBLE (3650 3000);
FORCEPROP 2 LAST TOLERANCE 20%
J 2
(3750 3000);
DISPLAY 0.553191 (3750 3000);
DISPLAY INVISIBLE (3750 3000);
FORCEPROP 1 LAST PATH I160
J 2
(3825 2950);
DISPLAY 0.723404 (3825 2950);
DISPLAY INVISIBLE (3825 2950);
FORCEPROP 1 LAST $LOCATION C876
J 0
(4075 3025);
DISPLAY 1.021277 (4075 3025);
DISPLAY INVISIBLE (4075 3025);
FORCEPROP 2 LAST CDS_LOCATION C876
J 0
(4075 3025);
DISPLAY 1.021277 (4075 3025);
DISPLAY INVISIBLE (4075 3025);
FORCEPROP 2 LAST $SEC 1
J 2
(4000 3025);
DISPLAY 0.680851 (4000 3025);
PAINT MONO (4000 3025);
DISPLAY INVISIBLE (4000 3025);
FORCEPROP 2 LAST CDS_SEC 1
J 2
(4000 3025);
DISPLAY 0.680851 (4000 3025);
DISPLAY INVISIBLE (4000 3025);
FORCEADD TAP..1
R 2
(3100 3150);
FORCEPROP 3 LASTPIN (3150 3150) SIG_NAME P5E_CPU0_PE3_TX_DN<13>
J 0
(3160 3160);
DISPLAY 0.659574 (3160 3160);
PAINT MONO (3160 3160);
DISPLAY INVISIBLE (3160 3160);
FORCEPROP 1 LASTPIN (3150 3150) BN 13
J 2
(3162 3158);
DISPLAY 0.680851 (3162 3158);
PAINT GREEN (3162 3158);
FORCEPROP 2 LAST CDS_LIB standard
J 0
(3100 3150);
DISPLAY INVISIBLE (3100 3150);
FORCEPROP 1 LAST BODY_TYPE PLUMBING
J 2
(3100 3200);
DISPLAY 0.872340 (3100 3200);
PAINT GREEN (3100 3200);
DISPLAY INVISIBLE (3100 3200);
FORCEPROP 1 LAST HDL_TAP TRUE
J 2
(2775 3025);
DISPLAY 0.872340 (2775 3025);
DISPLAY INVISIBLE (2775 3025);
FORCEPROP 1 LAST PATH I161
J 2
(3102 3150);
DISPLAY 0.872340 (3102 3150);
PAINT GREEN (3102 3150);
DISPLAY INVISIBLE (3102 3150);
FORCEADD TAP..1
R 2
(3100 3350);
FORCEPROP 3 LASTPIN (3150 3350) SIG_NAME P5E_CPU0_PE3_TX_DN<14>
J 0
(3160 3360);
DISPLAY 0.659574 (3160 3360);
PAINT MONO (3160 3360);
DISPLAY INVISIBLE (3160 3360);
FORCEPROP 1 LASTPIN (3150 3350) BN 14
J 2
(3162 3358);
DISPLAY 0.680851 (3162 3358);
PAINT GREEN (3162 3358);
FORCEPROP 2 LAST CDS_LIB standard
J 0
(3100 3350);
DISPLAY INVISIBLE (3100 3350);
FORCEPROP 1 LAST BODY_TYPE PLUMBING
J 2
(3100 3400);
DISPLAY 0.872340 (3100 3400);
PAINT GREEN (3100 3400);
DISPLAY INVISIBLE (3100 3400);
FORCEPROP 1 LAST HDL_TAP TRUE
J 2
(2775 3225);
DISPLAY 0.872340 (2775 3225);
DISPLAY INVISIBLE (2775 3225);
FORCEPROP 1 LAST PATH I162
J 2
(3102 3350);
DISPLAY 0.872340 (3102 3350);
PAINT GREEN (3102 3350);
DISPLAY INVISIBLE (3102 3350);
FORCEADD TAP..1
R 2
(3100 3550);
FORCEPROP 3 LASTPIN (3150 3550) SIG_NAME P5E_CPU0_PE3_TX_DN<15>
J 0
(3160 3560);
DISPLAY 0.659574 (3160 3560);
PAINT MONO (3160 3560);
DISPLAY INVISIBLE (3160 3560);
FORCEPROP 1 LASTPIN (3150 3550) BN 15
J 2
(3162 3558);
DISPLAY 0.680851 (3162 3558);
PAINT GREEN (3162 3558);
FORCEPROP 2 LAST CDS_LIB standard
J 0
(3100 3550);
DISPLAY INVISIBLE (3100 3550);
FORCEPROP 1 LAST BODY_TYPE PLUMBING
J 2
(3100 3600);
DISPLAY 0.872340 (3100 3600);
PAINT GREEN (3100 3600);
DISPLAY INVISIBLE (3100 3600);
FORCEPROP 1 LAST HDL_TAP TRUE
J 2
(2775 3425);
DISPLAY 0.872340 (2775 3425);
DISPLAY INVISIBLE (2775 3425);
FORCEPROP 1 LAST PATH I163
J 2
(3102 3550);
DISPLAY 0.872340 (3102 3550);
PAINT GREEN (3102 3550);
DISPLAY INVISIBLE (3102 3550);
FORCEADD Q_CAP_DIFFBUS..2
R 2
(3825 3100);
FORCEPROP 1 LAST PART_NUMBER SP_CH4221MEE01
J 2
(3709 3188);
DISPLAY 0.574468 (3709 3188);
PAINT GREEN (3709 3188);
DISPLAY INVISIBLE (3709 3188);
FORCEPROP 2 LAST VALUE DIFF BUS_0.22UF
J 2
(3675 3100);
DISPLAY 0.553191 (3675 3100);
FORCEPROP 1 LAST $LOCATION C875
J 2
(4059 3117);
DISPLAY 0.723404 (4059 3117);
PAINT GREEN (4059 3117);
FORCEPROP 2 LASTPIN (3900 3100) $PN 1
J 0
(3910 3110);
DISPLAY 0.808511 (3910 3110);
FORCEPROP 2 LASTPIN (3750 3100) $PN 2
J 2
(3740 3110);
DISPLAY 0.808511 (3740 3110);
FORCEPROP 1 LAST CDS_LMAN_SYM_OUTLINE -25,50,25,-50
J 2
(3825 3100);
DISPLAY 0.468085 (3825 3100);
PAINT GREEN (3825 3100);
DISPLAY INVISIBLE (3825 3100);
FORCEPROP 2 LAST CDS_LIB pure_quanta
J 2
(3825 3100);
DISPLAY INVISIBLE (3825 3100);
FORCEPROP 1 LAST PIN_NAMES_ROTATE TRUE
J 2
(3825 3100);
DISPLAY 0.489362 (3825 3100);
PAINT GREEN (3825 3100);
DISPLAY INVISIBLE (3825 3100);
FORCEPROP 2 LAST VOLTAGE 6.3V
J 2
(3475 3150);
DISPLAY 0.553191 (3475 3150);
DISPLAY INVISIBLE (3475 3150);
FORCEPROP 1 LAST MATERIAL X6S
J 2
(3834 3179);
DISPLAY 0.574468 (3834 3179);
PAINT GREEN (3834 3179);
DISPLAY INVISIBLE (3834 3179);
FORCEPROP 2 LAST PACK_TYPE C0201
J 2
(3650 3150);
DISPLAY 0.553191 (3650 3150);
DISPLAY INVISIBLE (3650 3150);
FORCEPROP 2 LAST TOLERANCE 20%
J 2
(3750 3150);
DISPLAY 0.553191 (3750 3150);
DISPLAY INVISIBLE (3750 3150);
FORCEPROP 1 LAST PATH I164
J 2
(3825 3100);
DISPLAY 0.723404 (3825 3100);
DISPLAY INVISIBLE (3825 3100);
FORCEPROP 1 LAST $LOCATION C875
J 0
(4075 3175);
DISPLAY 1.021277 (4075 3175);
DISPLAY INVISIBLE (4075 3175);
FORCEPROP 2 LAST CDS_LOCATION C875
J 0
(4075 3175);
DISPLAY 1.021277 (4075 3175);
DISPLAY INVISIBLE (4075 3175);
FORCEPROP 2 LAST $SEC 1
J 2
(4000 3175);
DISPLAY 0.680851 (4000 3175);
PAINT MONO (4000 3175);
DISPLAY INVISIBLE (4000 3175);
FORCEPROP 2 LAST CDS_SEC 1
J 2
(4000 3175);
DISPLAY 0.680851 (4000 3175);
DISPLAY INVISIBLE (4000 3175);
FORCEADD Q_CAP_DIFFBUS..2
R 2
(3825 3150);
FORCEPROP 1 LAST PART_NUMBER SP_CH4221MEE01
J 2
(3709 3238);
DISPLAY 0.574468 (3709 3238);
PAINT GREEN (3709 3238);
DISPLAY INVISIBLE (3709 3238);
FORCEPROP 2 LAST VALUE DIFF BUS_0.22UF
J 2
(3675 3150);
DISPLAY 0.553191 (3675 3150);
FORCEPROP 1 LAST $LOCATION C874
J 2
(4059 3167);
DISPLAY 0.723404 (4059 3167);
PAINT GREEN (4059 3167);
FORCEPROP 2 LASTPIN (3900 3150) $PN 1
J 0
(3910 3160);
DISPLAY 0.808511 (3910 3160);
FORCEPROP 2 LASTPIN (3750 3150) $PN 2
J 2
(3740 3160);
DISPLAY 0.808511 (3740 3160);
FORCEPROP 1 LAST CDS_LMAN_SYM_OUTLINE -25,50,25,-50
J 2
(3825 3150);
DISPLAY 0.468085 (3825 3150);
PAINT GREEN (3825 3150);
DISPLAY INVISIBLE (3825 3150);
FORCEPROP 2 LAST CDS_LIB pure_quanta
J 2
(3825 3150);
DISPLAY INVISIBLE (3825 3150);
FORCEPROP 1 LAST PIN_NAMES_ROTATE TRUE
J 2
(3825 3150);
DISPLAY 0.489362 (3825 3150);
PAINT GREEN (3825 3150);
DISPLAY INVISIBLE (3825 3150);
FORCEPROP 2 LAST VOLTAGE 6.3V
J 2
(3475 3200);
DISPLAY 0.553191 (3475 3200);
DISPLAY INVISIBLE (3475 3200);
FORCEPROP 1 LAST MATERIAL X6S
J 2
(3834 3229);
DISPLAY 0.574468 (3834 3229);
PAINT GREEN (3834 3229);
DISPLAY INVISIBLE (3834 3229);
FORCEPROP 2 LAST PACK_TYPE C0201
J 2
(3650 3200);
DISPLAY 0.553191 (3650 3200);
DISPLAY INVISIBLE (3650 3200);
FORCEPROP 2 LAST TOLERANCE 20%
J 2
(3750 3200);
DISPLAY 0.553191 (3750 3200);
DISPLAY INVISIBLE (3750 3200);
FORCEPROP 1 LAST PATH I165
J 2
(3825 3150);
DISPLAY 0.723404 (3825 3150);
DISPLAY INVISIBLE (3825 3150);
FORCEPROP 1 LAST $LOCATION C874
J 0
(4075 3225);
DISPLAY 1.021277 (4075 3225);
DISPLAY INVISIBLE (4075 3225);
FORCEPROP 2 LAST CDS_LOCATION C874
J 0
(4075 3225);
DISPLAY 1.021277 (4075 3225);
DISPLAY INVISIBLE (4075 3225);
FORCEPROP 2 LAST $SEC 1
J 2
(4000 3225);
DISPLAY 0.680851 (4000 3225);
PAINT MONO (4000 3225);
DISPLAY INVISIBLE (4000 3225);
FORCEPROP 2 LAST CDS_SEC 1
J 2
(4000 3225);
DISPLAY 0.680851 (4000 3225);
DISPLAY INVISIBLE (4000 3225);
FORCEADD Q_CAP_DIFFBUS..2
R 2
(3825 3300);
FORCEPROP 1 LAST PART_NUMBER SP_CH4221MEE01
J 2
(3709 3388);
DISPLAY 0.574468 (3709 3388);
PAINT GREEN (3709 3388);
DISPLAY INVISIBLE (3709 3388);
FORCEPROP 2 LAST VALUE DIFF BUS_0.22UF
J 2
(3675 3300);
DISPLAY 0.553191 (3675 3300);
FORCEPROP 1 LAST $LOCATION C873
J 2
(4059 3317);
DISPLAY 0.723404 (4059 3317);
PAINT GREEN (4059 3317);
FORCEPROP 2 LASTPIN (3900 3300) $PN 1
J 0
(3910 3310);
DISPLAY 0.808511 (3910 3310);
FORCEPROP 2 LASTPIN (3750 3300) $PN 2
J 2
(3740 3310);
DISPLAY 0.808511 (3740 3310);
FORCEPROP 1 LAST CDS_LMAN_SYM_OUTLINE -25,50,25,-50
J 2
(3825 3300);
DISPLAY 0.468085 (3825 3300);
PAINT GREEN (3825 3300);
DISPLAY INVISIBLE (3825 3300);
FORCEPROP 2 LAST CDS_LIB pure_quanta
J 2
(3825 3300);
DISPLAY INVISIBLE (3825 3300);
FORCEPROP 1 LAST PIN_NAMES_ROTATE TRUE
J 2
(3825 3300);
DISPLAY 0.489362 (3825 3300);
PAINT GREEN (3825 3300);
DISPLAY INVISIBLE (3825 3300);
FORCEPROP 2 LAST VOLTAGE 6.3V
J 2
(3475 3350);
DISPLAY 0.553191 (3475 3350);
DISPLAY INVISIBLE (3475 3350);
FORCEPROP 1 LAST MATERIAL X6S
J 2
(3834 3379);
DISPLAY 0.574468 (3834 3379);
PAINT GREEN (3834 3379);
DISPLAY INVISIBLE (3834 3379);
FORCEPROP 2 LAST PACK_TYPE C0201
J 2
(3650 3350);
DISPLAY 0.553191 (3650 3350);
DISPLAY INVISIBLE (3650 3350);
FORCEPROP 2 LAST TOLERANCE 20%
J 2
(3750 3350);
DISPLAY 0.553191 (3750 3350);
DISPLAY INVISIBLE (3750 3350);
FORCEPROP 1 LAST PATH I166
J 2
(3825 3300);
DISPLAY 0.723404 (3825 3300);
DISPLAY INVISIBLE (3825 3300);
FORCEPROP 1 LAST $LOCATION C873
J 0
(4075 3375);
DISPLAY 1.021277 (4075 3375);
DISPLAY INVISIBLE (4075 3375);
FORCEPROP 2 LAST CDS_LOCATION C873
J 0
(4075 3375);
DISPLAY 1.021277 (4075 3375);
DISPLAY INVISIBLE (4075 3375);
FORCEPROP 2 LAST $SEC 1
J 2
(4000 3375);
DISPLAY 0.680851 (4000 3375);
PAINT MONO (4000 3375);
DISPLAY INVISIBLE (4000 3375);
FORCEPROP 2 LAST CDS_SEC 1
J 2
(4000 3375);
DISPLAY 0.680851 (4000 3375);
DISPLAY INVISIBLE (4000 3375);
FORCEADD Q_CAP_DIFFBUS..2
R 2
(3825 3350);
FORCEPROP 1 LAST PART_NUMBER SP_CH4221MEE01
J 2
(3709 3438);
DISPLAY 0.574468 (3709 3438);
PAINT GREEN (3709 3438);
DISPLAY INVISIBLE (3709 3438);
FORCEPROP 2 LAST VALUE DIFF BUS_0.22UF
J 2
(3675 3350);
DISPLAY 0.553191 (3675 3350);
FORCEPROP 1 LAST $LOCATION C872
J 2
(4059 3367);
DISPLAY 0.723404 (4059 3367);
PAINT GREEN (4059 3367);
FORCEPROP 2 LASTPIN (3900 3350) $PN 1
J 0
(3910 3360);
DISPLAY 0.808511 (3910 3360);
FORCEPROP 2 LASTPIN (3750 3350) $PN 2
J 2
(3740 3360);
DISPLAY 0.808511 (3740 3360);
FORCEPROP 1 LAST CDS_LMAN_SYM_OUTLINE -25,50,25,-50
J 2
(3825 3350);
DISPLAY 0.468085 (3825 3350);
PAINT GREEN (3825 3350);
DISPLAY INVISIBLE (3825 3350);
FORCEPROP 2 LAST CDS_LIB pure_quanta
J 2
(3825 3350);
DISPLAY INVISIBLE (3825 3350);
FORCEPROP 1 LAST PIN_NAMES_ROTATE TRUE
J 2
(3825 3350);
DISPLAY 0.489362 (3825 3350);
PAINT GREEN (3825 3350);
DISPLAY INVISIBLE (3825 3350);
FORCEPROP 2 LAST VOLTAGE 6.3V
J 2
(3475 3400);
DISPLAY 0.553191 (3475 3400);
DISPLAY INVISIBLE (3475 3400);
FORCEPROP 1 LAST MATERIAL X6S
J 2
(3834 3429);
DISPLAY 0.574468 (3834 3429);
PAINT GREEN (3834 3429);
DISPLAY INVISIBLE (3834 3429);
FORCEPROP 2 LAST PACK_TYPE C0201
J 2
(3650 3400);
DISPLAY 0.553191 (3650 3400);
DISPLAY INVISIBLE (3650 3400);
FORCEPROP 2 LAST TOLERANCE 20%
J 2
(3750 3400);
DISPLAY 0.553191 (3750 3400);
DISPLAY INVISIBLE (3750 3400);
FORCEPROP 1 LAST PATH I167
J 2
(3825 3350);
DISPLAY 0.723404 (3825 3350);
DISPLAY INVISIBLE (3825 3350);
FORCEPROP 1 LAST $LOCATION C872
J 0
(4075 3425);
DISPLAY 1.021277 (4075 3425);
DISPLAY INVISIBLE (4075 3425);
FORCEPROP 2 LAST CDS_LOCATION C872
J 0
(4075 3425);
DISPLAY 1.021277 (4075 3425);
DISPLAY INVISIBLE (4075 3425);
FORCEPROP 2 LAST $SEC 1
J 2
(4000 3425);
DISPLAY 0.680851 (4000 3425);
PAINT MONO (4000 3425);
DISPLAY INVISIBLE (4000 3425);
FORCEPROP 2 LAST CDS_SEC 1
J 2
(4000 3425);
DISPLAY 0.680851 (4000 3425);
DISPLAY INVISIBLE (4000 3425);
FORCEADD Q_CAP_DIFFBUS..2
R 2
(3825 3500);
FORCEPROP 1 LAST PART_NUMBER SP_CH4221MEE01
J 2
(3709 3588);
DISPLAY 0.574468 (3709 3588);
PAINT GREEN (3709 3588);
DISPLAY INVISIBLE (3709 3588);
FORCEPROP 2 LAST VALUE DIFF BUS_0.22UF
J 2
(3675 3500);
DISPLAY 0.553191 (3675 3500);
FORCEPROP 1 LAST $LOCATION C871
J 2
(4059 3517);
DISPLAY 0.723404 (4059 3517);
PAINT GREEN (4059 3517);
FORCEPROP 2 LASTPIN (3900 3500) $PN 1
J 0
(3910 3510);
DISPLAY 0.808511 (3910 3510);
FORCEPROP 2 LASTPIN (3750 3500) $PN 2
J 2
(3740 3510);
DISPLAY 0.808511 (3740 3510);
FORCEPROP 1 LAST CDS_LMAN_SYM_OUTLINE -25,50,25,-50
J 2
(3825 3500);
DISPLAY 0.468085 (3825 3500);
PAINT GREEN (3825 3500);
DISPLAY INVISIBLE (3825 3500);
FORCEPROP 2 LAST CDS_LIB pure_quanta
J 2
(3825 3500);
DISPLAY INVISIBLE (3825 3500);
FORCEPROP 1 LAST PIN_NAMES_ROTATE TRUE
J 2
(3825 3500);
DISPLAY 0.489362 (3825 3500);
PAINT GREEN (3825 3500);
DISPLAY INVISIBLE (3825 3500);
FORCEPROP 2 LAST VOLTAGE 6.3V
J 2
(3475 3550);
DISPLAY 0.553191 (3475 3550);
DISPLAY INVISIBLE (3475 3550);
FORCEPROP 1 LAST MATERIAL X6S
J 2
(3834 3579);
DISPLAY 0.574468 (3834 3579);
PAINT GREEN (3834 3579);
DISPLAY INVISIBLE (3834 3579);
FORCEPROP 2 LAST PACK_TYPE C0201
J 2
(3650 3550);
DISPLAY 0.553191 (3650 3550);
DISPLAY INVISIBLE (3650 3550);
FORCEPROP 2 LAST TOLERANCE 20%
J 2
(3750 3550);
DISPLAY 0.553191 (3750 3550);
DISPLAY INVISIBLE (3750 3550);
FORCEPROP 1 LAST PATH I168
J 2
(3825 3500);
DISPLAY 0.723404 (3825 3500);
DISPLAY INVISIBLE (3825 3500);
FORCEPROP 1 LAST $LOCATION C871
J 0
(4075 3575);
DISPLAY 1.021277 (4075 3575);
DISPLAY INVISIBLE (4075 3575);
FORCEPROP 2 LAST CDS_LOCATION C871
J 0
(4075 3575);
DISPLAY 1.021277 (4075 3575);
DISPLAY INVISIBLE (4075 3575);
FORCEPROP 2 LAST $SEC 1
J 2
(4000 3575);
DISPLAY 0.680851 (4000 3575);
PAINT MONO (4000 3575);
DISPLAY INVISIBLE (4000 3575);
FORCEPROP 2 LAST CDS_SEC 1
J 2
(4000 3575);
DISPLAY 0.680851 (4000 3575);
DISPLAY INVISIBLE (4000 3575);
FORCEADD Q_CAP_DIFFBUS..2
R 2
(3825 3550);
FORCEPROP 1 LAST PART_NUMBER SP_CH4221MEE01
J 2
(4084 3638);
DISPLAY 0.574468 (4084 3638);
PAINT GREEN (4084 3638);
DISPLAY INVISIBLE (4084 3638);
FORCEPROP 1 LAST MATERIAL X6S
J 2
(3784 3754);
DISPLAY 0.574468 (3784 3754);
PAINT GREEN (3784 3754);
FORCEPROP 2 LAST VALUE DIFF BUS_0.22UF
J 2
(3675 3550);
DISPLAY 0.553191 (3675 3550);
FORCEPROP 2 LAST VOLTAGE 6.3V
J 2
(4075 3700);
DISPLAY 0.553191 (4075 3700);
PAINT GREEN (4075 3700);
FORCEPROP 2 LAST TOLERANCE 20%
J 2
(3925 3700);
DISPLAY 0.553191 (3925 3700);
PAINT GREEN (3925 3700);
FORCEPROP 2 LAST PACK_TYPE C0201
J 2
(3825 3700);
DISPLAY 0.553191 (3825 3700);
PAINT GREEN (3825 3700);
FORCEPROP 1 LAST $LOCATION C870
J 2
(4059 3567);
DISPLAY 0.723404 (4059 3567);
PAINT GREEN (4059 3567);
FORCEPROP 2 LASTPIN (3900 3550) $PN 1
J 0
(3910 3560);
DISPLAY 0.808511 (3910 3560);
FORCEPROP 2 LASTPIN (3750 3550) $PN 2
J 2
(3740 3560);
DISPLAY 0.808511 (3740 3560);
FORCEPROP 2 LAST CDS_LIB pure_quanta
J 2
(3825 3550);
DISPLAY INVISIBLE (3825 3550);
FORCEPROP 1 LAST CDS_LMAN_SYM_OUTLINE -25,50,25,-50
J 2
(3825 3550);
DISPLAY 0.468085 (3825 3550);
PAINT GREEN (3825 3550);
DISPLAY INVISIBLE (3825 3550);
FORCEPROP 1 LAST PIN_NAMES_ROTATE TRUE
J 2
(3825 3550);
DISPLAY 0.489362 (3825 3550);
PAINT GREEN (3825 3550);
DISPLAY INVISIBLE (3825 3550);
FORCEPROP 1 LAST PATH I169
J 2
(3825 3550);
DISPLAY 0.723404 (3825 3550);
DISPLAY INVISIBLE (3825 3550);
FORCEPROP 1 LAST $LOCATION C870
J 0
(4075 3625);
DISPLAY 1.021277 (4075 3625);
DISPLAY INVISIBLE (4075 3625);
FORCEPROP 2 LAST CDS_LOCATION C870
J 0
(3800 3800);
DISPLAY 1.021277 (3800 3800);
DISPLAY INVISIBLE (3800 3800);
FORCEPROP 2 LAST $SEC 1
J 2
(4000 3625);
DISPLAY 0.680851 (4000 3625);
PAINT MONO (4000 3625);
DISPLAY INVISIBLE (4000 3625);
FORCEPROP 2 LAST CDS_SEC 1
J 2
(4000 3625);
DISPLAY 0.680851 (4000 3625);
DISPLAY INVISIBLE (4000 3625);
FORCEADD TAP..1
R 2
(-1625 1525);
FORCEPROP 3 LASTPIN (-1575 1525) SIG_NAME P5E_CPU0_PE1_TX_DP<7>
J 0
(-1565 1535);
DISPLAY 0.659574 (-1565 1535);
PAINT MONO (-1565 1535);
DISPLAY INVISIBLE (-1565 1535);
FORCEPROP 1 LASTPIN (-1575 1525) BN 7
J 2
(-1563 1533);
DISPLAY 0.680851 (-1563 1533);
PAINT GREEN (-1563 1533);
FORCEPROP 2 LAST CDS_LIB standard
J 0
(-1625 1525);
DISPLAY INVISIBLE (-1625 1525);
FORCEPROP 1 LAST BODY_TYPE PLUMBING
J 2
(-1625 1575);
DISPLAY 0.872340 (-1625 1575);
PAINT GREEN (-1625 1575);
DISPLAY INVISIBLE (-1625 1575);
FORCEPROP 1 LAST HDL_TAP TRUE
J 2
(-1950 1400);
DISPLAY 0.872340 (-1950 1400);
DISPLAY INVISIBLE (-1950 1400);
FORCEPROP 1 LAST PATH I17
J 2
(-1623 1525);
DISPLAY 0.872340 (-1623 1525);
PAINT GREEN (-1623 1525);
DISPLAY INVISIBLE (-1623 1525);
FORCEADD TAP..1
(4375 175);
FORCEPROP 3 LASTPIN (4325 175) SIG_NAME P5E_CPU0_PE3_TX_C_DN<0>
J 0
(4335 185);
DISPLAY 0.659574 (4335 185);
PAINT MONO (4335 185);
DISPLAY INVISIBLE (4335 185);
FORCEPROP 1 LASTPIN (4325 175) BN 0
J 0
(4313 183);
DISPLAY 0.680851 (4313 183);
PAINT GREEN (4313 183);
FORCEPROP 2 LAST CDS_LIB standard
J 0
(4375 175);
DISPLAY INVISIBLE (4375 175);
FORCEPROP 1 LAST BODY_TYPE PLUMBING
J 0
(4375 225);
DISPLAY 0.872340 (4375 225);
PAINT GREEN (4375 225);
DISPLAY INVISIBLE (4375 225);
FORCEPROP 1 LAST HDL_TAP TRUE
J 0
(4700 50);
DISPLAY 0.872340 (4700 50);
DISPLAY INVISIBLE (4700 50);
FORCEPROP 1 LAST PATH I170
J 0
(4373 175);
DISPLAY 0.872340 (4373 175);
PAINT GREEN (4373 175);
DISPLAY INVISIBLE (4373 175);
FORCEADD TAP..1
(4375 375);
FORCEPROP 3 LASTPIN (4325 375) SIG_NAME P5E_CPU0_PE3_TX_C_DN<1>
J 0
(4335 385);
DISPLAY 0.659574 (4335 385);
PAINT MONO (4335 385);
DISPLAY INVISIBLE (4335 385);
FORCEPROP 1 LASTPIN (4325 375) BN 1
J 0
(4313 383);
DISPLAY 0.680851 (4313 383);
PAINT GREEN (4313 383);
FORCEPROP 2 LAST CDS_LIB standard
J 0
(4375 375);
DISPLAY INVISIBLE (4375 375);
FORCEPROP 1 LAST BODY_TYPE PLUMBING
J 0
(4375 425);
DISPLAY 0.872340 (4375 425);
PAINT GREEN (4375 425);
DISPLAY INVISIBLE (4375 425);
FORCEPROP 1 LAST HDL_TAP TRUE
J 0
(4700 250);
DISPLAY 0.872340 (4700 250);
DISPLAY INVISIBLE (4700 250);
FORCEPROP 1 LAST PATH I171
J 0
(4373 375);
DISPLAY 0.872340 (4373 375);
PAINT GREEN (4373 375);
DISPLAY INVISIBLE (4373 375);
FORCEADD TAP..1
(4375 575);
FORCEPROP 3 LASTPIN (4325 575) SIG_NAME P5E_CPU0_PE3_TX_C_DN<2>
J 0
(4335 585);
DISPLAY 0.659574 (4335 585);
PAINT MONO (4335 585);
DISPLAY INVISIBLE (4335 585);
FORCEPROP 1 LASTPIN (4325 575) BN 2
J 0
(4313 583);
DISPLAY 0.680851 (4313 583);
PAINT GREEN (4313 583);
FORCEPROP 2 LAST CDS_LIB standard
J 0
(4375 575);
DISPLAY INVISIBLE (4375 575);
FORCEPROP 1 LAST BODY_TYPE PLUMBING
J 0
(4375 625);
DISPLAY 0.872340 (4375 625);
PAINT GREEN (4375 625);
DISPLAY INVISIBLE (4375 625);
FORCEPROP 1 LAST HDL_TAP TRUE
J 0
(4700 450);
DISPLAY 0.872340 (4700 450);
DISPLAY INVISIBLE (4700 450);
FORCEPROP 1 LAST PATH I172
J 0
(4373 575);
DISPLAY 0.872340 (4373 575);
PAINT GREEN (4373 575);
DISPLAY INVISIBLE (4373 575);
FORCEADD TAP..1
(4375 975);
FORCEPROP 3 LASTPIN (4325 975) SIG_NAME P5E_CPU0_PE3_TX_C_DN<4>
J 0
(4335 985);
DISPLAY 0.659574 (4335 985);
PAINT MONO (4335 985);
DISPLAY INVISIBLE (4335 985);
FORCEPROP 1 LASTPIN (4325 975) BN 4
J 0
(4313 983);
DISPLAY 0.680851 (4313 983);
PAINT GREEN (4313 983);
FORCEPROP 2 LAST CDS_LIB standard
J 0
(4375 975);
DISPLAY INVISIBLE (4375 975);
FORCEPROP 1 LAST BODY_TYPE PLUMBING
J 0
(4375 1025);
DISPLAY 0.872340 (4375 1025);
PAINT GREEN (4375 1025);
DISPLAY INVISIBLE (4375 1025);
FORCEPROP 1 LAST HDL_TAP TRUE
J 0
(4700 850);
DISPLAY 0.872340 (4700 850);
DISPLAY INVISIBLE (4700 850);
FORCEPROP 1 LAST PATH I173
J 0
(4373 975);
DISPLAY 0.872340 (4373 975);
PAINT GREEN (4373 975);
DISPLAY INVISIBLE (4373 975);
FORCEADD TAP..1
(4375 775);
FORCEPROP 3 LASTPIN (4325 775) SIG_NAME P5E_CPU0_PE3_TX_C_DN<3>
J 0
(4335 785);
DISPLAY 0.659574 (4335 785);
PAINT MONO (4335 785);
DISPLAY INVISIBLE (4335 785);
FORCEPROP 1 LASTPIN (4325 775) BN 3
J 0
(4313 783);
DISPLAY 0.680851 (4313 783);
PAINT GREEN (4313 783);
FORCEPROP 2 LAST CDS_LIB standard
J 0
(4375 775);
DISPLAY INVISIBLE (4375 775);
FORCEPROP 1 LAST BODY_TYPE PLUMBING
J 0
(4375 825);
DISPLAY 0.872340 (4375 825);
PAINT GREEN (4375 825);
DISPLAY INVISIBLE (4375 825);
FORCEPROP 1 LAST HDL_TAP TRUE
J 0
(4700 650);
DISPLAY 0.872340 (4700 650);
DISPLAY INVISIBLE (4700 650);
FORCEPROP 1 LAST PATH I174
J 0
(4373 775);
DISPLAY 0.872340 (4373 775);
PAINT GREEN (4373 775);
DISPLAY INVISIBLE (4373 775);
FORCEADD TAP..1
(4575 125);
FORCEPROP 3 LASTPIN (4525 125) SIG_NAME P5E_CPU0_PE3_TX_C_DP<0>
J 0
(4535 135);
DISPLAY 0.659574 (4535 135);
PAINT MONO (4535 135);
DISPLAY INVISIBLE (4535 135);
FORCEPROP 1 LASTPIN (4525 125) BN 0
J 0
(4513 133);
DISPLAY 0.680851 (4513 133);
PAINT GREEN (4513 133);
FORCEPROP 2 LAST CDS_LIB standard
J 0
(4575 125);
DISPLAY INVISIBLE (4575 125);
FORCEPROP 1 LAST BODY_TYPE PLUMBING
J 0
(4575 175);
DISPLAY 0.872340 (4575 175);
PAINT GREEN (4575 175);
DISPLAY INVISIBLE (4575 175);
FORCEPROP 1 LAST HDL_TAP TRUE
J 0
(4900 0);
DISPLAY 0.872340 (4900 0);
DISPLAY INVISIBLE (4900 0);
FORCEPROP 1 LAST PATH I175
J 0
(4573 125);
DISPLAY 0.872340 (4573 125);
PAINT GREEN (4573 125);
DISPLAY INVISIBLE (4573 125);
FORCEADD TAP..1
(4575 325);
FORCEPROP 3 LASTPIN (4525 325) SIG_NAME P5E_CPU0_PE3_TX_C_DP<1>
J 0
(4535 335);
DISPLAY 0.659574 (4535 335);
PAINT MONO (4535 335);
DISPLAY INVISIBLE (4535 335);
FORCEPROP 1 LASTPIN (4525 325) BN 1
J 0
(4513 333);
DISPLAY 0.680851 (4513 333);
PAINT GREEN (4513 333);
FORCEPROP 2 LAST CDS_LIB standard
J 0
(4575 325);
DISPLAY INVISIBLE (4575 325);
FORCEPROP 1 LAST BODY_TYPE PLUMBING
J 0
(4575 375);
DISPLAY 0.872340 (4575 375);
PAINT GREEN (4575 375);
DISPLAY INVISIBLE (4575 375);
FORCEPROP 1 LAST HDL_TAP TRUE
J 0
(4900 200);
DISPLAY 0.872340 (4900 200);
DISPLAY INVISIBLE (4900 200);
FORCEPROP 1 LAST PATH I176
J 0
(4573 325);
DISPLAY 0.872340 (4573 325);
PAINT GREEN (4573 325);
DISPLAY INVISIBLE (4573 325);
FORCEADD TAP..1
(4575 525);
FORCEPROP 3 LASTPIN (4525 525) SIG_NAME P5E_CPU0_PE3_TX_C_DP<2>
J 0
(4535 535);
DISPLAY 0.659574 (4535 535);
PAINT MONO (4535 535);
DISPLAY INVISIBLE (4535 535);
FORCEPROP 1 LASTPIN (4525 525) BN 2
J 0
(4513 533);
DISPLAY 0.680851 (4513 533);
PAINT GREEN (4513 533);
FORCEPROP 2 LAST CDS_LIB standard
J 0
(4575 525);
DISPLAY INVISIBLE (4575 525);
FORCEPROP 1 LAST BODY_TYPE PLUMBING
J 0
(4575 575);
DISPLAY 0.872340 (4575 575);
PAINT GREEN (4575 575);
DISPLAY INVISIBLE (4575 575);
FORCEPROP 1 LAST HDL_TAP TRUE
J 0
(4900 400);
DISPLAY 0.872340 (4900 400);
DISPLAY INVISIBLE (4900 400);
FORCEPROP 1 LAST PATH I177
J 0
(4573 525);
DISPLAY 0.872340 (4573 525);
PAINT GREEN (4573 525);
DISPLAY INVISIBLE (4573 525);
FORCEADD TAP..1
(4575 725);
FORCEPROP 3 LASTPIN (4525 725) SIG_NAME P5E_CPU0_PE3_TX_C_DP<3>
J 0
(4535 735);
DISPLAY 0.659574 (4535 735);
PAINT MONO (4535 735);
DISPLAY INVISIBLE (4535 735);
FORCEPROP 1 LASTPIN (4525 725) BN 3
J 0
(4513 733);
DISPLAY 0.680851 (4513 733);
PAINT GREEN (4513 733);
FORCEPROP 2 LAST CDS_LIB standard
J 0
(4575 725);
DISPLAY INVISIBLE (4575 725);
FORCEPROP 1 LAST BODY_TYPE PLUMBING
J 0
(4575 775);
DISPLAY 0.872340 (4575 775);
PAINT GREEN (4575 775);
DISPLAY INVISIBLE (4575 775);
FORCEPROP 1 LAST HDL_TAP TRUE
J 0
(4900 600);
DISPLAY 0.872340 (4900 600);
DISPLAY INVISIBLE (4900 600);
FORCEPROP 1 LAST PATH I178
J 0
(4573 725);
DISPLAY 0.872340 (4573 725);
PAINT GREEN (4573 725);
DISPLAY INVISIBLE (4573 725);
FORCEADD TAP..1
(4575 925);
FORCEPROP 3 LASTPIN (4525 925) SIG_NAME P5E_CPU0_PE3_TX_C_DP<4>
J 0
(4535 935);
DISPLAY 0.659574 (4535 935);
PAINT MONO (4535 935);
DISPLAY INVISIBLE (4535 935);
FORCEPROP 1 LASTPIN (4525 925) BN 4
J 0
(4513 933);
DISPLAY 0.680851 (4513 933);
PAINT GREEN (4513 933);
FORCEPROP 2 LAST CDS_LIB standard
J 0
(4575 925);
DISPLAY INVISIBLE (4575 925);
FORCEPROP 1 LAST BODY_TYPE PLUMBING
J 0
(4575 975);
DISPLAY 0.872340 (4575 975);
PAINT GREEN (4575 975);
DISPLAY INVISIBLE (4575 975);
FORCEPROP 1 LAST HDL_TAP TRUE
J 0
(4900 800);
DISPLAY 0.872340 (4900 800);
DISPLAY INVISIBLE (4900 800);
FORCEPROP 1 LAST PATH I179
J 0
(4573 925);
DISPLAY 0.872340 (4573 925);
PAINT GREEN (4573 925);
DISPLAY INVISIBLE (4573 925);
FORCEADD TAP..1
R 2
(-1375 1175);
FORCEPROP 3 LASTPIN (-1325 1175) SIG_NAME P5E_CPU0_PE1_TX_DN<5>
J 0
(-1315 1185);
DISPLAY 0.659574 (-1315 1185);
PAINT MONO (-1315 1185);
DISPLAY INVISIBLE (-1315 1185);
FORCEPROP 1 LASTPIN (-1325 1175) BN 5
J 2
(-1313 1183);
DISPLAY 0.680851 (-1313 1183);
PAINT GREEN (-1313 1183);
FORCEPROP 2 LAST CDS_LIB standard
J 0
(-1375 1175);
DISPLAY INVISIBLE (-1375 1175);
FORCEPROP 1 LAST BODY_TYPE PLUMBING
J 2
(-1375 1225);
DISPLAY 0.872340 (-1375 1225);
PAINT GREEN (-1375 1225);
DISPLAY INVISIBLE (-1375 1225);
FORCEPROP 1 LAST HDL_TAP TRUE
J 2
(-1700 1050);
DISPLAY 0.872340 (-1700 1050);
DISPLAY INVISIBLE (-1700 1050);
FORCEPROP 1 LAST PATH I18
J 2
(-1373 1175);
DISPLAY 0.872340 (-1373 1175);
PAINT GREEN (-1373 1175);
DISPLAY INVISIBLE (-1373 1175);
FORCEADD TAP..1
(4375 1175);
FORCEPROP 3 LASTPIN (4325 1175) SIG_NAME P5E_CPU0_PE3_TX_C_DN<5>
J 0
(4335 1185);
DISPLAY 0.659574 (4335 1185);
PAINT MONO (4335 1185);
DISPLAY INVISIBLE (4335 1185);
FORCEPROP 1 LASTPIN (4325 1175) BN 5
J 0
(4313 1183);
DISPLAY 0.680851 (4313 1183);
PAINT GREEN (4313 1183);
FORCEPROP 2 LAST CDS_LIB standard
J 0
(4375 1175);
DISPLAY INVISIBLE (4375 1175);
FORCEPROP 1 LAST BODY_TYPE PLUMBING
J 0
(4375 1225);
DISPLAY 0.872340 (4375 1225);
PAINT GREEN (4375 1225);
DISPLAY INVISIBLE (4375 1225);
FORCEPROP 1 LAST HDL_TAP TRUE
J 0
(4700 1050);
DISPLAY 0.872340 (4700 1050);
DISPLAY INVISIBLE (4700 1050);
FORCEPROP 1 LAST PATH I180
J 0
(4373 1175);
DISPLAY 0.872340 (4373 1175);
PAINT GREEN (4373 1175);
DISPLAY INVISIBLE (4373 1175);
FORCEADD TAP..1
(4375 1375);
FORCEPROP 3 LASTPIN (4325 1375) SIG_NAME P5E_CPU0_PE3_TX_C_DN<6>
J 0
(4335 1385);
DISPLAY 0.659574 (4335 1385);
PAINT MONO (4335 1385);
DISPLAY INVISIBLE (4335 1385);
FORCEPROP 1 LASTPIN (4325 1375) BN 6
J 0
(4313 1383);
DISPLAY 0.680851 (4313 1383);
PAINT GREEN (4313 1383);
FORCEPROP 2 LAST CDS_LIB standard
J 0
(4375 1375);
DISPLAY INVISIBLE (4375 1375);
FORCEPROP 1 LAST BODY_TYPE PLUMBING
J 0
(4375 1425);
DISPLAY 0.872340 (4375 1425);
PAINT GREEN (4375 1425);
DISPLAY INVISIBLE (4375 1425);
FORCEPROP 1 LAST HDL_TAP TRUE
J 0
(4700 1250);
DISPLAY 0.872340 (4700 1250);
DISPLAY INVISIBLE (4700 1250);
FORCEPROP 1 LAST PATH I181
J 0
(4373 1375);
DISPLAY 0.872340 (4373 1375);
PAINT GREEN (4373 1375);
DISPLAY INVISIBLE (4373 1375);
FORCEADD TAP..1
(4375 1575);
FORCEPROP 3 LASTPIN (4325 1575) SIG_NAME P5E_CPU0_PE3_TX_C_DN<7>
J 0
(4335 1585);
DISPLAY 0.659574 (4335 1585);
PAINT MONO (4335 1585);
DISPLAY INVISIBLE (4335 1585);
FORCEPROP 1 LASTPIN (4325 1575) BN 7
J 0
(4313 1583);
DISPLAY 0.680851 (4313 1583);
PAINT GREEN (4313 1583);
FORCEPROP 2 LAST CDS_LIB standard
J 0
(4375 1575);
DISPLAY INVISIBLE (4375 1575);
FORCEPROP 1 LAST BODY_TYPE PLUMBING
J 0
(4375 1625);
DISPLAY 0.872340 (4375 1625);
PAINT GREEN (4375 1625);
DISPLAY INVISIBLE (4375 1625);
FORCEPROP 1 LAST HDL_TAP TRUE
J 0
(4700 1450);
DISPLAY 0.872340 (4700 1450);
DISPLAY INVISIBLE (4700 1450);
FORCEPROP 1 LAST PATH I182
J 0
(4373 1575);
DISPLAY 0.872340 (4373 1575);
PAINT GREEN (4373 1575);
DISPLAY INVISIBLE (4373 1575);
FORCEADD TAP..1
(4575 1125);
FORCEPROP 3 LASTPIN (4525 1125) SIG_NAME P5E_CPU0_PE3_TX_C_DP<5>
J 0
(4535 1135);
DISPLAY 0.659574 (4535 1135);
PAINT MONO (4535 1135);
DISPLAY INVISIBLE (4535 1135);
FORCEPROP 1 LASTPIN (4525 1125) BN 5
J 0
(4513 1133);
DISPLAY 0.680851 (4513 1133);
PAINT GREEN (4513 1133);
FORCEPROP 2 LAST CDS_LIB standard
J 0
(4575 1125);
DISPLAY INVISIBLE (4575 1125);
FORCEPROP 1 LAST BODY_TYPE PLUMBING
J 0
(4575 1175);
DISPLAY 0.872340 (4575 1175);
PAINT GREEN (4575 1175);
DISPLAY INVISIBLE (4575 1175);
FORCEPROP 1 LAST HDL_TAP TRUE
J 0
(4900 1000);
DISPLAY 0.872340 (4900 1000);
DISPLAY INVISIBLE (4900 1000);
FORCEPROP 1 LAST PATH I183
J 0
(4573 1125);
DISPLAY 0.872340 (4573 1125);
PAINT GREEN (4573 1125);
DISPLAY INVISIBLE (4573 1125);
FORCEADD TAP..1
(4575 1325);
FORCEPROP 3 LASTPIN (4525 1325) SIG_NAME P5E_CPU0_PE3_TX_C_DP<6>
J 0
(4535 1335);
DISPLAY 0.659574 (4535 1335);
PAINT MONO (4535 1335);
DISPLAY INVISIBLE (4535 1335);
FORCEPROP 1 LASTPIN (4525 1325) BN 6
J 0
(4513 1333);
DISPLAY 0.680851 (4513 1333);
PAINT GREEN (4513 1333);
FORCEPROP 2 LAST CDS_LIB standard
J 0
(4575 1325);
DISPLAY INVISIBLE (4575 1325);
FORCEPROP 1 LAST BODY_TYPE PLUMBING
J 0
(4575 1375);
DISPLAY 0.872340 (4575 1375);
PAINT GREEN (4575 1375);
DISPLAY INVISIBLE (4575 1375);
FORCEPROP 1 LAST HDL_TAP TRUE
J 0
(4900 1200);
DISPLAY 0.872340 (4900 1200);
DISPLAY INVISIBLE (4900 1200);
FORCEPROP 1 LAST PATH I184
J 0
(4573 1325);
DISPLAY 0.872340 (4573 1325);
PAINT GREEN (4573 1325);
DISPLAY INVISIBLE (4573 1325);
FORCEADD TAP..1
(4575 1525);
FORCEPROP 3 LASTPIN (4525 1525) SIG_NAME P5E_CPU0_PE3_TX_C_DP<7>
J 0
(4535 1535);
DISPLAY 0.659574 (4535 1535);
PAINT MONO (4535 1535);
DISPLAY INVISIBLE (4535 1535);
FORCEPROP 1 LASTPIN (4525 1525) BN 7
J 0
(4513 1533);
DISPLAY 0.680851 (4513 1533);
PAINT GREEN (4513 1533);
FORCEPROP 2 LAST CDS_LIB standard
J 0
(4575 1525);
DISPLAY INVISIBLE (4575 1525);
FORCEPROP 1 LAST BODY_TYPE PLUMBING
J 0
(4575 1575);
DISPLAY 0.872340 (4575 1575);
PAINT GREEN (4575 1575);
DISPLAY INVISIBLE (4575 1575);
FORCEPROP 1 LAST HDL_TAP TRUE
J 0
(4900 1400);
DISPLAY 0.872340 (4900 1400);
DISPLAY INVISIBLE (4900 1400);
FORCEPROP 1 LAST PATH I185
J 0
(4573 1525);
DISPLAY 0.872340 (4573 1525);
PAINT GREEN (4573 1525);
DISPLAY INVISIBLE (4573 1525);
FORCEADD OFFPAGE..2
(5575 1550);
FORCEPROP 2 LAST $XR0 136 
J 0
(5764 1550);
DISPLAY 0.638298 (5764 1550);
PAINT MONO (5764 1550);
FORCEPROP 2 LAST CDS_LIB standard
J 0
(5575 1550);
DISPLAY INVISIBLE (5575 1550);
FORCEPROP 1 LAST OFFPAGE TRUE
J 0
(5900 1425);
DISPLAY 0.872340 (5900 1425);
DISPLAY INVISIBLE (5900 1425);
FORCEPROP 1 LAST COMMENT_BODY TRUE
J 0
(5530 1455);
DISPLAY 0.872340 (5530 1455);
PAINT GREEN (5530 1455);
DISPLAY INVISIBLE (5530 1455);
FORCEPROP 2 LAST PATH I186
J 0
(5775 1600);
DISPLAY 1.021277 (5775 1600);
DISPLAY INVISIBLE (5775 1600);
FORCEADD OFFPAGE..2
(5575 1600);
FORCEPROP 2 LAST $XR0 136 
J 0
(5764 1600);
DISPLAY 0.638298 (5764 1600);
PAINT MONO (5764 1600);
FORCEPROP 2 LAST CDS_LIB standard
J 0
(5575 1600);
DISPLAY INVISIBLE (5575 1600);
FORCEPROP 1 LAST OFFPAGE TRUE
J 0
(5900 1475);
DISPLAY 0.872340 (5900 1475);
DISPLAY INVISIBLE (5900 1475);
FORCEPROP 1 LAST COMMENT_BODY TRUE
J 0
(5530 1505);
DISPLAY 0.872340 (5530 1505);
PAINT GREEN (5530 1505);
DISPLAY INVISIBLE (5530 1505);
FORCEPROP 2 LAST PATH I187
J 0
(5775 1650);
DISPLAY 1.021277 (5775 1650);
DISPLAY INVISIBLE (5775 1650);
FORCEADD TAP..1
(4375 2150);
FORCEPROP 3 LASTPIN (4325 2150) SIG_NAME P5E_CPU0_PE3_TX_C_DN<8>
J 0
(4335 2160);
DISPLAY 0.659574 (4335 2160);
PAINT MONO (4335 2160);
DISPLAY INVISIBLE (4335 2160);
FORCEPROP 1 LASTPIN (4325 2150) BN 8
J 0
(4313 2158);
DISPLAY 0.680851 (4313 2158);
PAINT GREEN (4313 2158);
FORCEPROP 2 LAST CDS_LIB standard
J 0
(4375 2150);
DISPLAY INVISIBLE (4375 2150);
FORCEPROP 1 LAST BODY_TYPE PLUMBING
J 0
(4375 2200);
DISPLAY 0.872340 (4375 2200);
PAINT GREEN (4375 2200);
DISPLAY INVISIBLE (4375 2200);
FORCEPROP 1 LAST HDL_TAP TRUE
J 0
(4700 2025);
DISPLAY 0.872340 (4700 2025);
DISPLAY INVISIBLE (4700 2025);
FORCEPROP 1 LAST PATH I188
J 0
(4373 2150);
DISPLAY 0.872340 (4373 2150);
PAINT GREEN (4373 2150);
DISPLAY INVISIBLE (4373 2150);
FORCEADD TAP..1
(4375 2350);
FORCEPROP 3 LASTPIN (4325 2350) SIG_NAME P5E_CPU0_PE3_TX_C_DN<9>
J 0
(4335 2360);
DISPLAY 0.659574 (4335 2360);
PAINT MONO (4335 2360);
DISPLAY INVISIBLE (4335 2360);
FORCEPROP 1 LASTPIN (4325 2350) BN 9
J 0
(4313 2358);
DISPLAY 0.680851 (4313 2358);
PAINT GREEN (4313 2358);
FORCEPROP 2 LAST CDS_LIB standard
J 0
(4375 2350);
DISPLAY INVISIBLE (4375 2350);
FORCEPROP 1 LAST BODY_TYPE PLUMBING
J 0
(4375 2400);
DISPLAY 0.872340 (4375 2400);
PAINT GREEN (4375 2400);
DISPLAY INVISIBLE (4375 2400);
FORCEPROP 1 LAST HDL_TAP TRUE
J 0
(4700 2225);
DISPLAY 0.872340 (4700 2225);
DISPLAY INVISIBLE (4700 2225);
FORCEPROP 1 LAST PATH I189
J 0
(4373 2350);
DISPLAY 0.872340 (4373 2350);
PAINT GREEN (4373 2350);
DISPLAY INVISIBLE (4373 2350);
FORCEADD TAP..1
R 2
(-1375 1375);
FORCEPROP 3 LASTPIN (-1325 1375) SIG_NAME P5E_CPU0_PE1_TX_DN<6>
J 0
(-1315 1385);
DISPLAY 0.659574 (-1315 1385);
PAINT MONO (-1315 1385);
DISPLAY INVISIBLE (-1315 1385);
FORCEPROP 1 LASTPIN (-1325 1375) BN 6
J 2
(-1313 1383);
DISPLAY 0.680851 (-1313 1383);
PAINT GREEN (-1313 1383);
FORCEPROP 2 LAST CDS_LIB standard
J 0
(-1375 1375);
DISPLAY INVISIBLE (-1375 1375);
FORCEPROP 1 LAST BODY_TYPE PLUMBING
J 2
(-1375 1425);
DISPLAY 0.872340 (-1375 1425);
PAINT GREEN (-1375 1425);
DISPLAY INVISIBLE (-1375 1425);
FORCEPROP 1 LAST HDL_TAP TRUE
J 2
(-1700 1250);
DISPLAY 0.872340 (-1700 1250);
DISPLAY INVISIBLE (-1700 1250);
FORCEPROP 1 LAST PATH I19
J 2
(-1373 1375);
DISPLAY 0.872340 (-1373 1375);
PAINT GREEN (-1373 1375);
DISPLAY INVISIBLE (-1373 1375);
FORCEADD TAP..1
(4375 2550);
FORCEPROP 3 LASTPIN (4325 2550) SIG_NAME P5E_CPU0_PE3_TX_C_DN<10>
J 0
(4335 2560);
DISPLAY 0.659574 (4335 2560);
PAINT MONO (4335 2560);
DISPLAY INVISIBLE (4335 2560);
FORCEPROP 1 LASTPIN (4325 2550) BN 10
J 0
(4313 2558);
DISPLAY 0.680851 (4313 2558);
PAINT GREEN (4313 2558);
FORCEPROP 2 LAST CDS_LIB standard
J 0
(4375 2550);
DISPLAY INVISIBLE (4375 2550);
FORCEPROP 1 LAST BODY_TYPE PLUMBING
J 0
(4375 2600);
DISPLAY 0.872340 (4375 2600);
PAINT GREEN (4375 2600);
DISPLAY INVISIBLE (4375 2600);
FORCEPROP 1 LAST HDL_TAP TRUE
J 0
(4700 2425);
DISPLAY 0.872340 (4700 2425);
DISPLAY INVISIBLE (4700 2425);
FORCEPROP 1 LAST PATH I190
J 0
(4373 2550);
DISPLAY 0.872340 (4373 2550);
PAINT GREEN (4373 2550);
DISPLAY INVISIBLE (4373 2550);
FORCEADD TAP..1
(4375 2750);
FORCEPROP 3 LASTPIN (4325 2750) SIG_NAME P5E_CPU0_PE3_TX_C_DN<11>
J 0
(4335 2760);
DISPLAY 0.659574 (4335 2760);
PAINT MONO (4335 2760);
DISPLAY INVISIBLE (4335 2760);
FORCEPROP 1 LASTPIN (4325 2750) BN 11
J 0
(4313 2758);
DISPLAY 0.680851 (4313 2758);
PAINT GREEN (4313 2758);
FORCEPROP 2 LAST CDS_LIB standard
J 0
(4375 2750);
DISPLAY INVISIBLE (4375 2750);
FORCEPROP 1 LAST BODY_TYPE PLUMBING
J 0
(4375 2800);
DISPLAY 0.872340 (4375 2800);
PAINT GREEN (4375 2800);
DISPLAY INVISIBLE (4375 2800);
FORCEPROP 1 LAST HDL_TAP TRUE
J 0
(4700 2625);
DISPLAY 0.872340 (4700 2625);
DISPLAY INVISIBLE (4700 2625);
FORCEPROP 1 LAST PATH I191
J 0
(4373 2750);
DISPLAY 0.872340 (4373 2750);
PAINT GREEN (4373 2750);
DISPLAY INVISIBLE (4373 2750);
FORCEADD TAP..1
(4375 2950);
FORCEPROP 3 LASTPIN (4325 2950) SIG_NAME P5E_CPU0_PE3_TX_C_DN<12>
J 0
(4335 2960);
DISPLAY 0.659574 (4335 2960);
PAINT MONO (4335 2960);
DISPLAY INVISIBLE (4335 2960);
FORCEPROP 1 LASTPIN (4325 2950) BN 12
J 0
(4313 2958);
DISPLAY 0.680851 (4313 2958);
PAINT GREEN (4313 2958);
FORCEPROP 2 LAST CDS_LIB standard
J 0
(4375 2950);
DISPLAY INVISIBLE (4375 2950);
FORCEPROP 1 LAST BODY_TYPE PLUMBING
J 0
(4375 3000);
DISPLAY 0.872340 (4375 3000);
PAINT GREEN (4375 3000);
DISPLAY INVISIBLE (4375 3000);
FORCEPROP 1 LAST HDL_TAP TRUE
J 0
(4700 2825);
DISPLAY 0.872340 (4700 2825);
DISPLAY INVISIBLE (4700 2825);
FORCEPROP 1 LAST PATH I192
J 0
(4373 2950);
DISPLAY 0.872340 (4373 2950);
PAINT GREEN (4373 2950);
DISPLAY INVISIBLE (4373 2950);
FORCEADD TAP..1
(4575 2100);
FORCEPROP 3 LASTPIN (4525 2100) SIG_NAME P5E_CPU0_PE3_TX_C_DP<8>
J 0
(4535 2110);
DISPLAY 0.659574 (4535 2110);
PAINT MONO (4535 2110);
DISPLAY INVISIBLE (4535 2110);
FORCEPROP 1 LASTPIN (4525 2100) BN 8
J 0
(4513 2108);
DISPLAY 0.680851 (4513 2108);
PAINT GREEN (4513 2108);
FORCEPROP 2 LAST CDS_LIB standard
J 0
(4575 2100);
DISPLAY INVISIBLE (4575 2100);
FORCEPROP 1 LAST BODY_TYPE PLUMBING
J 0
(4575 2150);
DISPLAY 0.872340 (4575 2150);
PAINT GREEN (4575 2150);
DISPLAY INVISIBLE (4575 2150);
FORCEPROP 1 LAST HDL_TAP TRUE
J 0
(4900 1975);
DISPLAY 0.872340 (4900 1975);
DISPLAY INVISIBLE (4900 1975);
FORCEPROP 1 LAST PATH I193
J 0
(4573 2100);
DISPLAY 0.872340 (4573 2100);
PAINT GREEN (4573 2100);
DISPLAY INVISIBLE (4573 2100);
FORCEADD TAP..1
(4575 2300);
FORCEPROP 3 LASTPIN (4525 2300) SIG_NAME P5E_CPU0_PE3_TX_C_DP<9>
J 0
(4535 2310);
DISPLAY 0.659574 (4535 2310);
PAINT MONO (4535 2310);
DISPLAY INVISIBLE (4535 2310);
FORCEPROP 1 LASTPIN (4525 2300) BN 9
J 0
(4513 2308);
DISPLAY 0.680851 (4513 2308);
PAINT GREEN (4513 2308);
FORCEPROP 2 LAST CDS_LIB standard
J 0
(4575 2300);
DISPLAY INVISIBLE (4575 2300);
FORCEPROP 1 LAST BODY_TYPE PLUMBING
J 0
(4575 2350);
DISPLAY 0.872340 (4575 2350);
PAINT GREEN (4575 2350);
DISPLAY INVISIBLE (4575 2350);
FORCEPROP 1 LAST HDL_TAP TRUE
J 0
(4900 2175);
DISPLAY 0.872340 (4900 2175);
DISPLAY INVISIBLE (4900 2175);
FORCEPROP 1 LAST PATH I194
J 0
(4573 2300);
DISPLAY 0.872340 (4573 2300);
PAINT GREEN (4573 2300);
DISPLAY INVISIBLE (4573 2300);
FORCEADD TAP..1
(4575 2500);
FORCEPROP 3 LASTPIN (4525 2500) SIG_NAME P5E_CPU0_PE3_TX_C_DP<10>
J 0
(4535 2510);
DISPLAY 0.659574 (4535 2510);
PAINT MONO (4535 2510);
DISPLAY INVISIBLE (4535 2510);
FORCEPROP 1 LASTPIN (4525 2500) BN 10
J 0
(4513 2508);
DISPLAY 0.680851 (4513 2508);
PAINT GREEN (4513 2508);
FORCEPROP 2 LAST CDS_LIB standard
J 0
(4575 2500);
DISPLAY INVISIBLE (4575 2500);
FORCEPROP 1 LAST BODY_TYPE PLUMBING
J 0
(4575 2550);
DISPLAY 0.872340 (4575 2550);
PAINT GREEN (4575 2550);
DISPLAY INVISIBLE (4575 2550);
FORCEPROP 1 LAST HDL_TAP TRUE
J 0
(4900 2375);
DISPLAY 0.872340 (4900 2375);
DISPLAY INVISIBLE (4900 2375);
FORCEPROP 1 LAST PATH I195
J 0
(4573 2500);
DISPLAY 0.872340 (4573 2500);
PAINT GREEN (4573 2500);
DISPLAY INVISIBLE (4573 2500);
FORCEADD TAP..1
(4575 2700);
FORCEPROP 3 LASTPIN (4525 2700) SIG_NAME P5E_CPU0_PE3_TX_C_DP<11>
J 0
(4535 2710);
DISPLAY 0.659574 (4535 2710);
PAINT MONO (4535 2710);
DISPLAY INVISIBLE (4535 2710);
FORCEPROP 1 LASTPIN (4525 2700) BN 11
J 0
(4513 2708);
DISPLAY 0.680851 (4513 2708);
PAINT GREEN (4513 2708);
FORCEPROP 2 LAST CDS_LIB standard
J 0
(4575 2700);
DISPLAY INVISIBLE (4575 2700);
FORCEPROP 1 LAST BODY_TYPE PLUMBING
J 0
(4575 2750);
DISPLAY 0.872340 (4575 2750);
PAINT GREEN (4575 2750);
DISPLAY INVISIBLE (4575 2750);
FORCEPROP 1 LAST HDL_TAP TRUE
J 0
(4900 2575);
DISPLAY 0.872340 (4900 2575);
DISPLAY INVISIBLE (4900 2575);
FORCEPROP 1 LAST PATH I196
J 0
(4573 2700);
DISPLAY 0.872340 (4573 2700);
PAINT GREEN (4573 2700);
DISPLAY INVISIBLE (4573 2700);
FORCEADD TAP..1
(4575 2900);
FORCEPROP 3 LASTPIN (4525 2900) SIG_NAME P5E_CPU0_PE3_TX_C_DP<12>
J 0
(4535 2910);
DISPLAY 0.659574 (4535 2910);
PAINT MONO (4535 2910);
DISPLAY INVISIBLE (4535 2910);
FORCEPROP 1 LASTPIN (4525 2900) BN 12
J 0
(4513 2908);
DISPLAY 0.680851 (4513 2908);
PAINT GREEN (4513 2908);
FORCEPROP 2 LAST CDS_LIB standard
J 0
(4575 2900);
DISPLAY INVISIBLE (4575 2900);
FORCEPROP 1 LAST BODY_TYPE PLUMBING
J 0
(4575 2950);
DISPLAY 0.872340 (4575 2950);
PAINT GREEN (4575 2950);
DISPLAY INVISIBLE (4575 2950);
FORCEPROP 1 LAST HDL_TAP TRUE
J 0
(4900 2775);
DISPLAY 0.872340 (4900 2775);
DISPLAY INVISIBLE (4900 2775);
FORCEPROP 1 LAST PATH I197
J 0
(4573 2900);
DISPLAY 0.872340 (4573 2900);
PAINT GREEN (4573 2900);
DISPLAY INVISIBLE (4573 2900);
FORCEADD TAP..1
(4375 3150);
FORCEPROP 3 LASTPIN (4325 3150) SIG_NAME P5E_CPU0_PE3_TX_C_DN<13>
J 0
(4335 3160);
DISPLAY 0.659574 (4335 3160);
PAINT MONO (4335 3160);
DISPLAY INVISIBLE (4335 3160);
FORCEPROP 1 LASTPIN (4325 3150) BN 13
J 0
(4313 3158);
DISPLAY 0.680851 (4313 3158);
PAINT GREEN (4313 3158);
FORCEPROP 2 LAST CDS_LIB standard
J 0
(4375 3150);
DISPLAY INVISIBLE (4375 3150);
FORCEPROP 1 LAST BODY_TYPE PLUMBING
J 0
(4375 3200);
DISPLAY 0.872340 (4375 3200);
PAINT GREEN (4375 3200);
DISPLAY INVISIBLE (4375 3200);
FORCEPROP 1 LAST HDL_TAP TRUE
J 0
(4700 3025);
DISPLAY 0.872340 (4700 3025);
DISPLAY INVISIBLE (4700 3025);
FORCEPROP 1 LAST PATH I198
J 0
(4373 3150);
DISPLAY 0.872340 (4373 3150);
PAINT GREEN (4373 3150);
DISPLAY INVISIBLE (4373 3150);
FORCEADD TAP..1
(4375 3550);
FORCEPROP 3 LASTPIN (4325 3550) SIG_NAME P5E_CPU0_PE3_TX_C_DN<15>
J 0
(4335 3560);
DISPLAY 0.659574 (4335 3560);
PAINT MONO (4335 3560);
DISPLAY INVISIBLE (4335 3560);
FORCEPROP 1 LASTPIN (4325 3550) BN 15
J 0
(4313 3558);
DISPLAY 0.680851 (4313 3558);
PAINT GREEN (4313 3558);
FORCEPROP 2 LAST CDS_LIB standard
J 0
(4375 3550);
DISPLAY INVISIBLE (4375 3550);
FORCEPROP 1 LAST BODY_TYPE PLUMBING
J 0
(4375 3600);
DISPLAY 0.872340 (4375 3600);
PAINT GREEN (4375 3600);
DISPLAY INVISIBLE (4375 3600);
FORCEPROP 1 LAST HDL_TAP TRUE
J 0
(4700 3425);
DISPLAY 0.872340 (4700 3425);
DISPLAY INVISIBLE (4700 3425);
FORCEPROP 1 LAST PATH I199
J 0
(4373 3550);
DISPLAY 0.872340 (4373 3550);
PAINT GREEN (4373 3550);
DISPLAY INVISIBLE (4373 3550);
FORCEADD OFFPAGE..1
(-2575 1550);
FORCEPROP 2 LAST $XR0 29 
J 0
(-2796 1550);
DISPLAY 0.638298 (-2796 1550);
PAINT MONO (-2796 1550);
FORCEPROP 2 LAST CDS_LIB standard
J 0
(-2575 1550);
DISPLAY INVISIBLE (-2575 1550);
FORCEPROP 1 LAST OFFPAGE TRUE
J 0
(-2250 1425);
DISPLAY 0.872340 (-2250 1425);
DISPLAY INVISIBLE (-2250 1425);
FORCEPROP 1 LAST COMMENT_BODY TRUE
J 0
(-2450 1450);
DISPLAY 0.872340 (-2450 1450);
PAINT GREEN (-2450 1450);
DISPLAY INVISIBLE (-2450 1450);
FORCEPROP 2 LAST PATH I2
J 0
(-2825 1600);
DISPLAY 1.021277 (-2825 1600);
DISPLAY INVISIBLE (-2825 1600);
FORCEADD TAP..1
R 2
(-1375 1575);
FORCEPROP 3 LASTPIN (-1325 1575) SIG_NAME P5E_CPU0_PE1_TX_DN<7>
J 0
(-1315 1585);
DISPLAY 0.659574 (-1315 1585);
PAINT MONO (-1315 1585);
DISPLAY INVISIBLE (-1315 1585);
FORCEPROP 1 LASTPIN (-1325 1575) BN 7
J 2
(-1313 1583);
DISPLAY 0.680851 (-1313 1583);
PAINT GREEN (-1313 1583);
FORCEPROP 2 LAST CDS_LIB standard
J 0
(-1375 1575);
DISPLAY INVISIBLE (-1375 1575);
FORCEPROP 1 LAST BODY_TYPE PLUMBING
J 2
(-1375 1625);
DISPLAY 0.872340 (-1375 1625);
PAINT GREEN (-1375 1625);
DISPLAY INVISIBLE (-1375 1625);
FORCEPROP 1 LAST HDL_TAP TRUE
J 2
(-1700 1450);
DISPLAY 0.872340 (-1700 1450);
DISPLAY INVISIBLE (-1700 1450);
FORCEPROP 1 LAST PATH I20
J 2
(-1373 1575);
DISPLAY 0.872340 (-1373 1575);
PAINT GREEN (-1373 1575);
DISPLAY INVISIBLE (-1373 1575);
FORCEADD TAP..1
(4375 3350);
FORCEPROP 3 LASTPIN (4325 3350) SIG_NAME P5E_CPU0_PE3_TX_C_DN<14>
J 0
(4335 3360);
DISPLAY 0.659574 (4335 3360);
PAINT MONO (4335 3360);
DISPLAY INVISIBLE (4335 3360);
FORCEPROP 1 LASTPIN (4325 3350) BN 14
J 0
(4313 3358);
DISPLAY 0.680851 (4313 3358);
PAINT GREEN (4313 3358);
FORCEPROP 2 LAST CDS_LIB standard
J 0
(4375 3350);
DISPLAY INVISIBLE (4375 3350);
FORCEPROP 1 LAST BODY_TYPE PLUMBING
J 0
(4375 3400);
DISPLAY 0.872340 (4375 3400);
PAINT GREEN (4375 3400);
DISPLAY INVISIBLE (4375 3400);
FORCEPROP 1 LAST HDL_TAP TRUE
J 0
(4700 3225);
DISPLAY 0.872340 (4700 3225);
DISPLAY INVISIBLE (4700 3225);
FORCEPROP 1 LAST PATH I200
J 0
(4373 3350);
DISPLAY 0.872340 (4373 3350);
PAINT GREEN (4373 3350);
DISPLAY INVISIBLE (4373 3350);
FORCEADD TAP..1
(4575 3100);
FORCEPROP 3 LASTPIN (4525 3100) SIG_NAME P5E_CPU0_PE3_TX_C_DP<13>
J 0
(4535 3110);
DISPLAY 0.659574 (4535 3110);
PAINT MONO (4535 3110);
DISPLAY INVISIBLE (4535 3110);
FORCEPROP 1 LASTPIN (4525 3100) BN 13
J 0
(4513 3108);
DISPLAY 0.680851 (4513 3108);
PAINT GREEN (4513 3108);
FORCEPROP 2 LAST CDS_LIB standard
J 0
(4575 3100);
DISPLAY INVISIBLE (4575 3100);
FORCEPROP 1 LAST BODY_TYPE PLUMBING
J 0
(4575 3150);
DISPLAY 0.872340 (4575 3150);
PAINT GREEN (4575 3150);
DISPLAY INVISIBLE (4575 3150);
FORCEPROP 1 LAST HDL_TAP TRUE
J 0
(4900 2975);
DISPLAY 0.872340 (4900 2975);
DISPLAY INVISIBLE (4900 2975);
FORCEPROP 1 LAST PATH I201
J 0
(4573 3100);
DISPLAY 0.872340 (4573 3100);
PAINT GREEN (4573 3100);
DISPLAY INVISIBLE (4573 3100);
FORCEADD TAP..1
(4575 3300);
FORCEPROP 3 LASTPIN (4525 3300) SIG_NAME P5E_CPU0_PE3_TX_C_DP<14>
J 0
(4535 3310);
DISPLAY 0.659574 (4535 3310);
PAINT MONO (4535 3310);
DISPLAY INVISIBLE (4535 3310);
FORCEPROP 1 LASTPIN (4525 3300) BN 14
J 0
(4513 3308);
DISPLAY 0.680851 (4513 3308);
PAINT GREEN (4513 3308);
FORCEPROP 2 LAST CDS_LIB standard
J 0
(4575 3300);
DISPLAY INVISIBLE (4575 3300);
FORCEPROP 1 LAST BODY_TYPE PLUMBING
J 0
(4575 3350);
DISPLAY 0.872340 (4575 3350);
PAINT GREEN (4575 3350);
DISPLAY INVISIBLE (4575 3350);
FORCEPROP 1 LAST HDL_TAP TRUE
J 0
(4900 3175);
DISPLAY 0.872340 (4900 3175);
DISPLAY INVISIBLE (4900 3175);
FORCEPROP 1 LAST PATH I202
J 0
(4573 3300);
DISPLAY 0.872340 (4573 3300);
PAINT GREEN (4573 3300);
DISPLAY INVISIBLE (4573 3300);
FORCEADD TAP..1
(4575 3500);
FORCEPROP 3 LASTPIN (4525 3500) SIG_NAME P5E_CPU0_PE3_TX_C_DP<15>
J 0
(4535 3510);
DISPLAY 0.659574 (4535 3510);
PAINT MONO (4535 3510);
DISPLAY INVISIBLE (4535 3510);
FORCEPROP 1 LASTPIN (4525 3500) BN 15
J 0
(4513 3508);
DISPLAY 0.680851 (4513 3508);
PAINT GREEN (4513 3508);
FORCEPROP 2 LAST CDS_LIB standard
J 0
(4575 3500);
DISPLAY INVISIBLE (4575 3500);
FORCEPROP 1 LAST BODY_TYPE PLUMBING
J 0
(4575 3550);
DISPLAY 0.872340 (4575 3550);
PAINT GREEN (4575 3550);
DISPLAY INVISIBLE (4575 3550);
FORCEPROP 1 LAST HDL_TAP TRUE
J 0
(4900 3375);
DISPLAY 0.872340 (4900 3375);
DISPLAY INVISIBLE (4900 3375);
FORCEPROP 1 LAST PATH I203
J 0
(4573 3500);
DISPLAY 0.872340 (4573 3500);
PAINT GREEN (4573 3500);
DISPLAY INVISIBLE (4573 3500);
FORCEADD OFFPAGE..2
(5575 3575);
FORCEPROP 2 LAST $XR0 137 
J 0
(5764 3575);
DISPLAY 0.638298 (5764 3575);
PAINT MONO (5764 3575);
FORCEPROP 2 LAST CDS_LIB standard
J 0
(5575 3575);
DISPLAY INVISIBLE (5575 3575);
FORCEPROP 1 LAST OFFPAGE TRUE
J 0
(5900 3450);
DISPLAY 0.872340 (5900 3450);
DISPLAY INVISIBLE (5900 3450);
FORCEPROP 1 LAST COMMENT_BODY TRUE
J 0
(5530 3480);
DISPLAY 0.872340 (5530 3480);
PAINT GREEN (5530 3480);
DISPLAY INVISIBLE (5530 3480);
FORCEPROP 2 LAST PATH I204
J 0
(5775 3625);
DISPLAY 1.021277 (5775 3625);
DISPLAY INVISIBLE (5775 3625);
FORCEADD OFFPAGE..2
(5575 3525);
FORCEPROP 2 LAST $XR0 137 
J 0
(5764 3525);
DISPLAY 0.638298 (5764 3525);
PAINT MONO (5764 3525);
FORCEPROP 2 LAST CDS_LIB standard
J 0
(5575 3525);
DISPLAY INVISIBLE (5575 3525);
FORCEPROP 1 LAST OFFPAGE TRUE
J 0
(5900 3400);
DISPLAY 0.872340 (5900 3400);
DISPLAY INVISIBLE (5900 3400);
FORCEPROP 1 LAST COMMENT_BODY TRUE
J 0
(5530 3430);
DISPLAY 0.872340 (5530 3430);
PAINT GREEN (5530 3430);
DISPLAY INVISIBLE (5530 3430);
FORCEPROP 2 LAST PATH I205
J 0
(5775 3575);
DISPLAY 1.021277 (5775 3575);
DISPLAY INVISIBLE (5775 3575);
FORCEADD Q_CAP_DIFFBUS..2
R 2
(3825 375);
FORCEPROP 1 LAST PART_NUMBER SP_CH4221MEE01
J 2
(3709 463);
DISPLAY 0.574468 (3709 463);
PAINT GREEN (3709 463);
DISPLAY INVISIBLE (3709 463);
FORCEPROP 2 LAST VALUE DIFF BUS_0.22UF
J 2
(3675 375);
DISPLAY 0.553191 (3675 375);
FORCEPROP 1 LAST $LOCATION C898
J 2
(4059 392);
DISPLAY 0.723404 (4059 392);
PAINT GREEN (4059 392);
FORCEPROP 2 LASTPIN (3900 375) $PN 1
J 0
(3910 385);
DISPLAY 0.808511 (3910 385);
FORCEPROP 2 LASTPIN (3750 375) $PN 2
J 2
(3740 385);
DISPLAY 0.808511 (3740 385);
FORCEPROP 1 LAST PIN_NAMES_ROTATE TRUE
J 2
(3825 375);
DISPLAY 0.489362 (3825 375);
PAINT GREEN (3825 375);
DISPLAY INVISIBLE (3825 375);
FORCEPROP 1 LAST CDS_LMAN_SYM_OUTLINE -25,50,25,-50
J 2
(3825 375);
DISPLAY 0.468085 (3825 375);
PAINT GREEN (3825 375);
DISPLAY INVISIBLE (3825 375);
FORCEPROP 2 LAST CDS_LIB pure_quanta
J 2
(3825 375);
DISPLAY INVISIBLE (3825 375);
FORCEPROP 2 LAST VOLTAGE 6.3V
J 2
(3475 425);
DISPLAY 0.553191 (3475 425);
DISPLAY INVISIBLE (3475 425);
FORCEPROP 1 LAST MATERIAL X6S
J 2
(3834 454);
DISPLAY 0.574468 (3834 454);
PAINT GREEN (3834 454);
DISPLAY INVISIBLE (3834 454);
FORCEPROP 2 LAST PACK_TYPE C0201
J 2
(3650 425);
DISPLAY 0.553191 (3650 425);
DISPLAY INVISIBLE (3650 425);
FORCEPROP 2 LAST TOLERANCE 20%
J 2
(3750 425);
DISPLAY 0.553191 (3750 425);
DISPLAY INVISIBLE (3750 425);
FORCEPROP 1 LAST PATH I206
J 2
(3825 375);
DISPLAY 0.723404 (3825 375);
DISPLAY INVISIBLE (3825 375);
FORCEPROP 1 LAST $LOCATION C898
J 0
(4075 450);
DISPLAY 1.021277 (4075 450);
DISPLAY INVISIBLE (4075 450);
FORCEPROP 2 LAST CDS_LOCATION C898
J 0
(4075 450);
DISPLAY 1.021277 (4075 450);
DISPLAY INVISIBLE (4075 450);
FORCEPROP 2 LAST $SEC 1
J 2
(4000 450);
DISPLAY 0.680851 (4000 450);
PAINT MONO (4000 450);
DISPLAY INVISIBLE (4000 450);
FORCEPROP 2 LAST CDS_SEC 1
J 2
(4000 450);
DISPLAY 0.680851 (4000 450);
DISPLAY INVISIBLE (4000 450);
FORCEADD TAP..1
R 2
(3100 975);
FORCEPROP 3 LASTPIN (3150 975) SIG_NAME P5E_CPU0_PE3_TX_DN<4>
J 0
(3160 985);
DISPLAY 0.659574 (3160 985);
PAINT MONO (3160 985);
DISPLAY INVISIBLE (3160 985);
FORCEPROP 1 LASTPIN (3150 975) BN 4
J 2
(3162 983);
DISPLAY 0.680851 (3162 983);
PAINT GREEN (3162 983);
FORCEPROP 2 LAST CDS_LIB standard
J 0
(3100 975);
DISPLAY INVISIBLE (3100 975);
FORCEPROP 1 LAST BODY_TYPE PLUMBING
J 2
(3100 1025);
DISPLAY 0.872340 (3100 1025);
PAINT GREEN (3100 1025);
DISPLAY INVISIBLE (3100 1025);
FORCEPROP 1 LAST HDL_TAP TRUE
J 2
(2775 850);
DISPLAY 0.872340 (2775 850);
DISPLAY INVISIBLE (2775 850);
FORCEPROP 1 LAST PATH I207
J 2
(3102 975);
DISPLAY 0.872340 (3102 975);
PAINT GREEN (3102 975);
DISPLAY INVISIBLE (3102 975);
FORCEADD TAP..1
R 2
(2850 1125);
FORCEPROP 3 LASTPIN (2900 1125) SIG_NAME P5E_CPU0_PE3_TX_DP<5>
J 0
(2910 1135);
DISPLAY 0.659574 (2910 1135);
PAINT MONO (2910 1135);
DISPLAY INVISIBLE (2910 1135);
FORCEPROP 1 LASTPIN (2900 1125) BN 5
J 2
(2912 1133);
DISPLAY 0.680851 (2912 1133);
PAINT GREEN (2912 1133);
FORCEPROP 2 LAST CDS_LIB standard
J 0
(2850 1125);
DISPLAY INVISIBLE (2850 1125);
FORCEPROP 1 LAST BODY_TYPE PLUMBING
J 2
(2850 1175);
DISPLAY 0.872340 (2850 1175);
PAINT GREEN (2850 1175);
DISPLAY INVISIBLE (2850 1175);
FORCEPROP 1 LAST HDL_TAP TRUE
J 2
(2525 1000);
DISPLAY 0.872340 (2525 1000);
DISPLAY INVISIBLE (2525 1000);
FORCEPROP 1 LAST PATH I208
J 2
(2852 1125);
DISPLAY 0.872340 (2852 1125);
PAINT GREEN (2852 1125);
DISPLAY INVISIBLE (2852 1125);
FORCEADD Q_CAP_DIFFBUS..2
R 2
(-650 125);
FORCEPROP 1 LAST PART_NUMBER SP_CH4221MEE01
J 2
(-766 213);
DISPLAY 0.574468 (-766 213);
PAINT GREEN (-766 213);
DISPLAY INVISIBLE (-766 213);
FORCEPROP 2 LAST VALUE DIFF BUS_0.22UF
J 2
(-800 125);
DISPLAY 0.553191 (-800 125);
FORCEPROP 1 LAST $LOCATION C869
J 2
(-416 142);
DISPLAY 0.723404 (-416 142);
PAINT GREEN (-416 142);
FORCEPROP 2 LASTPIN (-575 125) $PN 1
J 0
(-565 135);
DISPLAY 0.808511 (-565 135);
FORCEPROP 2 LASTPIN (-725 125) $PN 2
J 2
(-735 135);
DISPLAY 0.808511 (-735 135);
FORCEPROP 2 LAST TOLERANCE 20%
J 2
(-725 175);
DISPLAY 0.553191 (-725 175);
DISPLAY INVISIBLE (-725 175);
FORCEPROP 2 LAST PACK_TYPE C0201
J 2
(-825 175);
DISPLAY 0.553191 (-825 175);
DISPLAY INVISIBLE (-825 175);
FORCEPROP 1 LAST MATERIAL X6S
J 2
(-641 204);
DISPLAY 0.574468 (-641 204);
PAINT GREEN (-641 204);
DISPLAY INVISIBLE (-641 204);
FORCEPROP 2 LAST VOLTAGE 6.3V
J 2
(-1000 175);
DISPLAY 0.553191 (-1000 175);
DISPLAY INVISIBLE (-1000 175);
FORCEPROP 1 LAST CDS_LMAN_SYM_OUTLINE -25,50,25,-50
J 2
(-650 125);
DISPLAY 0.468085 (-650 125);
PAINT GREEN (-650 125);
DISPLAY INVISIBLE (-650 125);
FORCEPROP 2 LAST CDS_LIB pure_quanta
J 2
(-650 125);
DISPLAY INVISIBLE (-650 125);
FORCEPROP 1 LAST PIN_NAMES_ROTATE TRUE
J 2
(-650 125);
DISPLAY 0.489362 (-650 125);
PAINT GREEN (-650 125);
DISPLAY INVISIBLE (-650 125);
FORCEPROP 1 LAST PATH I21
J 2
(-650 125);
DISPLAY 0.723404 (-650 125);
DISPLAY INVISIBLE (-650 125);
FORCEPROP 1 LAST $LOCATION C869
J 0
(-400 200);
DISPLAY 1.021277 (-400 200);
DISPLAY INVISIBLE (-400 200);
FORCEPROP 2 LAST CDS_LOCATION C869
J 0
(-400 200);
DISPLAY 1.021277 (-400 200);
DISPLAY INVISIBLE (-400 200);
FORCEPROP 2 LAST $SEC 1
J 2
(-475 200);
DISPLAY 0.680851 (-475 200);
PAINT MONO (-475 200);
DISPLAY INVISIBLE (-475 200);
FORCEPROP 2 LAST CDS_SEC 1
J 2
(-475 200);
DISPLAY 0.680851 (-475 200);
DISPLAY INVISIBLE (-475 200);
FORCEADD Q_CAP_DIFFBUS..2
R 2
(-650 175);
FORCEPROP 1 LAST PART_NUMBER SP_CH4221MEE01
J 2
(-766 263);
DISPLAY 0.574468 (-766 263);
PAINT GREEN (-766 263);
DISPLAY INVISIBLE (-766 263);
FORCEPROP 2 LAST VALUE DIFF BUS_0.22UF
J 2
(-800 175);
DISPLAY 0.553191 (-800 175);
FORCEPROP 1 LAST $LOCATION C868
J 2
(-416 192);
DISPLAY 0.723404 (-416 192);
PAINT GREEN (-416 192);
FORCEPROP 2 LASTPIN (-575 175) $PN 1
J 0
(-565 185);
DISPLAY 0.808511 (-565 185);
FORCEPROP 2 LASTPIN (-725 175) $PN 2
J 2
(-735 185);
DISPLAY 0.808511 (-735 185);
FORCEPROP 2 LAST TOLERANCE 20%
J 2
(-725 225);
DISPLAY 0.553191 (-725 225);
DISPLAY INVISIBLE (-725 225);
FORCEPROP 2 LAST PACK_TYPE C0201
J 2
(-825 225);
DISPLAY 0.553191 (-825 225);
DISPLAY INVISIBLE (-825 225);
FORCEPROP 1 LAST MATERIAL X6S
J 2
(-641 254);
DISPLAY 0.574468 (-641 254);
PAINT GREEN (-641 254);
DISPLAY INVISIBLE (-641 254);
FORCEPROP 2 LAST VOLTAGE 6.3V
J 2
(-1000 225);
DISPLAY 0.553191 (-1000 225);
DISPLAY INVISIBLE (-1000 225);
FORCEPROP 1 LAST CDS_LMAN_SYM_OUTLINE -25,50,25,-50
J 2
(-650 175);
DISPLAY 0.468085 (-650 175);
PAINT GREEN (-650 175);
DISPLAY INVISIBLE (-650 175);
FORCEPROP 2 LAST CDS_LIB pure_quanta
J 2
(-650 175);
DISPLAY INVISIBLE (-650 175);
FORCEPROP 1 LAST PIN_NAMES_ROTATE TRUE
J 2
(-650 175);
DISPLAY 0.489362 (-650 175);
PAINT GREEN (-650 175);
DISPLAY INVISIBLE (-650 175);
FORCEPROP 1 LAST PATH I22
J 2
(-650 175);
DISPLAY 0.723404 (-650 175);
DISPLAY INVISIBLE (-650 175);
FORCEPROP 1 LAST $LOCATION C868
J 0
(-400 250);
DISPLAY 1.021277 (-400 250);
DISPLAY INVISIBLE (-400 250);
FORCEPROP 2 LAST CDS_LOCATION C868
J 0
(-400 250);
DISPLAY 1.021277 (-400 250);
DISPLAY INVISIBLE (-400 250);
FORCEPROP 2 LAST $SEC 1
J 2
(-475 250);
DISPLAY 0.680851 (-475 250);
PAINT MONO (-475 250);
DISPLAY INVISIBLE (-475 250);
FORCEPROP 2 LAST CDS_SEC 1
J 2
(-475 250);
DISPLAY 0.680851 (-475 250);
DISPLAY INVISIBLE (-475 250);
FORCEADD Q_CAP_DIFFBUS..2
R 2
(-650 325);
FORCEPROP 1 LAST PART_NUMBER SP_CH4221MEE01
J 2
(-766 413);
DISPLAY 0.574468 (-766 413);
PAINT GREEN (-766 413);
DISPLAY INVISIBLE (-766 413);
FORCEPROP 2 LAST VALUE DIFF BUS_0.22UF
J 2
(-800 325);
DISPLAY 0.553191 (-800 325);
FORCEPROP 1 LAST $LOCATION C867
J 2
(-416 342);
DISPLAY 0.723404 (-416 342);
PAINT GREEN (-416 342);
FORCEPROP 2 LASTPIN (-575 325) $PN 1
J 0
(-565 335);
DISPLAY 0.808511 (-565 335);
FORCEPROP 2 LASTPIN (-725 325) $PN 2
J 2
(-735 335);
DISPLAY 0.808511 (-735 335);
FORCEPROP 2 LAST TOLERANCE 20%
J 2
(-725 375);
DISPLAY 0.553191 (-725 375);
DISPLAY INVISIBLE (-725 375);
FORCEPROP 2 LAST PACK_TYPE C0201
J 2
(-825 375);
DISPLAY 0.553191 (-825 375);
DISPLAY INVISIBLE (-825 375);
FORCEPROP 1 LAST MATERIAL X6S
J 2
(-641 404);
DISPLAY 0.574468 (-641 404);
PAINT GREEN (-641 404);
DISPLAY INVISIBLE (-641 404);
FORCEPROP 2 LAST VOLTAGE 6.3V
J 2
(-1000 375);
DISPLAY 0.553191 (-1000 375);
DISPLAY INVISIBLE (-1000 375);
FORCEPROP 1 LAST CDS_LMAN_SYM_OUTLINE -25,50,25,-50
J 2
(-650 325);
DISPLAY 0.468085 (-650 325);
PAINT GREEN (-650 325);
DISPLAY INVISIBLE (-650 325);
FORCEPROP 2 LAST CDS_LIB pure_quanta
J 2
(-650 325);
DISPLAY INVISIBLE (-650 325);
FORCEPROP 1 LAST PIN_NAMES_ROTATE TRUE
J 2
(-650 325);
DISPLAY 0.489362 (-650 325);
PAINT GREEN (-650 325);
DISPLAY INVISIBLE (-650 325);
FORCEPROP 1 LAST PATH I23
J 2
(-650 325);
DISPLAY 0.723404 (-650 325);
DISPLAY INVISIBLE (-650 325);
FORCEPROP 1 LAST $LOCATION C867
J 0
(-400 400);
DISPLAY 1.021277 (-400 400);
DISPLAY INVISIBLE (-400 400);
FORCEPROP 2 LAST CDS_LOCATION C867
J 0
(-400 400);
DISPLAY 1.021277 (-400 400);
DISPLAY INVISIBLE (-400 400);
FORCEPROP 2 LAST $SEC 1
J 2
(-475 400);
DISPLAY 0.680851 (-475 400);
PAINT MONO (-475 400);
DISPLAY INVISIBLE (-475 400);
FORCEPROP 2 LAST CDS_SEC 1
J 2
(-475 400);
DISPLAY 0.680851 (-475 400);
DISPLAY INVISIBLE (-475 400);
FORCEADD Q_CAP_DIFFBUS..2
R 2
(-650 375);
FORCEPROP 1 LAST PART_NUMBER SP_CH4221MEE01
J 2
(-766 463);
DISPLAY 0.574468 (-766 463);
PAINT GREEN (-766 463);
DISPLAY INVISIBLE (-766 463);
FORCEPROP 2 LAST VALUE DIFF BUS_0.22UF
J 2
(-800 375);
DISPLAY 0.553191 (-800 375);
FORCEPROP 1 LAST $LOCATION C866
J 2
(-416 392);
DISPLAY 0.723404 (-416 392);
PAINT GREEN (-416 392);
FORCEPROP 2 LASTPIN (-575 375) $PN 1
J 0
(-565 385);
DISPLAY 0.808511 (-565 385);
FORCEPROP 2 LASTPIN (-725 375) $PN 2
J 2
(-735 385);
DISPLAY 0.808511 (-735 385);
FORCEPROP 2 LAST TOLERANCE 20%
J 2
(-725 425);
DISPLAY 0.553191 (-725 425);
DISPLAY INVISIBLE (-725 425);
FORCEPROP 2 LAST PACK_TYPE C0201
J 2
(-825 425);
DISPLAY 0.553191 (-825 425);
DISPLAY INVISIBLE (-825 425);
FORCEPROP 1 LAST MATERIAL X6S
J 2
(-641 454);
DISPLAY 0.574468 (-641 454);
PAINT GREEN (-641 454);
DISPLAY INVISIBLE (-641 454);
FORCEPROP 2 LAST VOLTAGE 6.3V
J 2
(-1000 425);
DISPLAY 0.553191 (-1000 425);
DISPLAY INVISIBLE (-1000 425);
FORCEPROP 2 LAST CDS_LIB pure_quanta
J 2
(-650 375);
DISPLAY INVISIBLE (-650 375);
FORCEPROP 1 LAST CDS_LMAN_SYM_OUTLINE -25,50,25,-50
J 2
(-650 375);
DISPLAY 0.468085 (-650 375);
PAINT GREEN (-650 375);
DISPLAY INVISIBLE (-650 375);
FORCEPROP 1 LAST PIN_NAMES_ROTATE TRUE
J 2
(-650 375);
DISPLAY 0.489362 (-650 375);
PAINT GREEN (-650 375);
DISPLAY INVISIBLE (-650 375);
FORCEPROP 1 LAST PATH I24
J 2
(-650 375);
DISPLAY 0.723404 (-650 375);
DISPLAY INVISIBLE (-650 375);
FORCEPROP 1 LAST $LOCATION C866
J 0
(-400 450);
DISPLAY 1.021277 (-400 450);
DISPLAY INVISIBLE (-400 450);
FORCEPROP 2 LAST CDS_LOCATION C866
J 0
(-400 450);
DISPLAY 1.021277 (-400 450);
DISPLAY INVISIBLE (-400 450);
FORCEPROP 2 LAST $SEC 1
J 2
(-475 450);
DISPLAY 0.680851 (-475 450);
PAINT MONO (-475 450);
DISPLAY INVISIBLE (-475 450);
FORCEPROP 2 LAST CDS_SEC 1
J 2
(-475 450);
DISPLAY 0.680851 (-475 450);
DISPLAY INVISIBLE (-475 450);
FORCEADD Q_CAP_DIFFBUS..2
R 2
(-650 575);
FORCEPROP 1 LAST PART_NUMBER SP_CH4221MEE01
J 2
(-766 663);
DISPLAY 0.574468 (-766 663);
PAINT GREEN (-766 663);
DISPLAY INVISIBLE (-766 663);
FORCEPROP 2 LAST VALUE DIFF BUS_0.22UF
J 2
(-800 575);
DISPLAY 0.553191 (-800 575);
FORCEPROP 1 LAST $LOCATION C864
J 2
(-416 592);
DISPLAY 0.723404 (-416 592);
PAINT GREEN (-416 592);
FORCEPROP 2 LASTPIN (-575 575) $PN 1
J 0
(-565 585);
DISPLAY 0.808511 (-565 585);
FORCEPROP 2 LASTPIN (-725 575) $PN 2
J 2
(-735 585);
DISPLAY 0.808511 (-735 585);
FORCEPROP 2 LAST TOLERANCE 20%
J 2
(-725 625);
DISPLAY 0.553191 (-725 625);
DISPLAY INVISIBLE (-725 625);
FORCEPROP 2 LAST PACK_TYPE C0201
J 2
(-825 625);
DISPLAY 0.553191 (-825 625);
DISPLAY INVISIBLE (-825 625);
FORCEPROP 1 LAST MATERIAL X6S
J 2
(-641 654);
DISPLAY 0.574468 (-641 654);
PAINT GREEN (-641 654);
DISPLAY INVISIBLE (-641 654);
FORCEPROP 2 LAST VOLTAGE 6.3V
J 2
(-1000 625);
DISPLAY 0.553191 (-1000 625);
DISPLAY INVISIBLE (-1000 625);
FORCEPROP 1 LAST CDS_LMAN_SYM_OUTLINE -25,50,25,-50
J 2
(-650 575);
DISPLAY 0.468085 (-650 575);
PAINT GREEN (-650 575);
DISPLAY INVISIBLE (-650 575);
FORCEPROP 2 LAST CDS_LIB pure_quanta
J 2
(-650 575);
DISPLAY INVISIBLE (-650 575);
FORCEPROP 1 LAST PIN_NAMES_ROTATE TRUE
J 2
(-650 575);
DISPLAY 0.489362 (-650 575);
PAINT GREEN (-650 575);
DISPLAY INVISIBLE (-650 575);
FORCEPROP 1 LAST PATH I25
J 2
(-650 575);
DISPLAY 0.723404 (-650 575);
DISPLAY INVISIBLE (-650 575);
FORCEPROP 1 LAST $LOCATION C864
J 0
(-400 650);
DISPLAY 1.021277 (-400 650);
DISPLAY INVISIBLE (-400 650);
FORCEPROP 2 LAST CDS_LOCATION C864
J 0
(-400 650);
DISPLAY 1.021277 (-400 650);
DISPLAY INVISIBLE (-400 650);
FORCEPROP 2 LAST $SEC 1
J 2
(-475 650);
DISPLAY 0.680851 (-475 650);
PAINT MONO (-475 650);
DISPLAY INVISIBLE (-475 650);
FORCEPROP 2 LAST CDS_SEC 1
J 2
(-475 650);
DISPLAY 0.680851 (-475 650);
DISPLAY INVISIBLE (-475 650);
FORCEADD Q_CAP_DIFFBUS..2
R 2
(-650 525);
FORCEPROP 1 LAST PART_NUMBER SP_CH4221MEE01
J 2
(-766 613);
DISPLAY 0.574468 (-766 613);
PAINT GREEN (-766 613);
DISPLAY INVISIBLE (-766 613);
FORCEPROP 2 LAST VALUE DIFF BUS_0.22UF
J 2
(-800 525);
DISPLAY 0.553191 (-800 525);
FORCEPROP 1 LAST $LOCATION C865
J 2
(-416 542);
DISPLAY 0.723404 (-416 542);
PAINT GREEN (-416 542);
FORCEPROP 2 LASTPIN (-575 525) $PN 1
J 0
(-565 535);
DISPLAY 0.808511 (-565 535);
FORCEPROP 2 LASTPIN (-725 525) $PN 2
J 2
(-735 535);
DISPLAY 0.808511 (-735 535);
FORCEPROP 2 LAST TOLERANCE 20%
J 2
(-725 575);
DISPLAY 0.553191 (-725 575);
DISPLAY INVISIBLE (-725 575);
FORCEPROP 2 LAST PACK_TYPE C0201
J 2
(-825 575);
DISPLAY 0.553191 (-825 575);
DISPLAY INVISIBLE (-825 575);
FORCEPROP 1 LAST MATERIAL X6S
J 2
(-641 604);
DISPLAY 0.574468 (-641 604);
PAINT GREEN (-641 604);
DISPLAY INVISIBLE (-641 604);
FORCEPROP 2 LAST VOLTAGE 6.3V
J 2
(-1000 575);
DISPLAY 0.553191 (-1000 575);
DISPLAY INVISIBLE (-1000 575);
FORCEPROP 1 LAST CDS_LMAN_SYM_OUTLINE -25,50,25,-50
J 2
(-650 525);
DISPLAY 0.468085 (-650 525);
PAINT GREEN (-650 525);
DISPLAY INVISIBLE (-650 525);
FORCEPROP 2 LAST CDS_LIB pure_quanta
J 2
(-650 525);
DISPLAY INVISIBLE (-650 525);
FORCEPROP 1 LAST PIN_NAMES_ROTATE TRUE
J 2
(-650 525);
DISPLAY 0.489362 (-650 525);
PAINT GREEN (-650 525);
DISPLAY INVISIBLE (-650 525);
FORCEPROP 1 LAST PATH I26
J 2
(-650 525);
DISPLAY 0.723404 (-650 525);
DISPLAY INVISIBLE (-650 525);
FORCEPROP 1 LAST $LOCATION C865
J 0
(-400 600);
DISPLAY 1.021277 (-400 600);
DISPLAY INVISIBLE (-400 600);
FORCEPROP 2 LAST CDS_LOCATION C865
J 0
(-400 600);
DISPLAY 1.021277 (-400 600);
DISPLAY INVISIBLE (-400 600);
FORCEPROP 2 LAST $SEC 1
J 2
(-475 600);
DISPLAY 0.680851 (-475 600);
PAINT MONO (-475 600);
DISPLAY INVISIBLE (-475 600);
FORCEPROP 2 LAST CDS_SEC 1
J 2
(-475 600);
DISPLAY 0.680851 (-475 600);
DISPLAY INVISIBLE (-475 600);
FORCEADD Q_CAP_DIFFBUS..2
R 2
(-650 725);
FORCEPROP 1 LAST PART_NUMBER SP_CH4221MEE01
J 2
(-766 813);
DISPLAY 0.574468 (-766 813);
PAINT GREEN (-766 813);
DISPLAY INVISIBLE (-766 813);
FORCEPROP 2 LAST VALUE DIFF BUS_0.22UF
J 2
(-800 725);
DISPLAY 0.553191 (-800 725);
FORCEPROP 1 LAST $LOCATION C863
J 2
(-416 742);
DISPLAY 0.723404 (-416 742);
PAINT GREEN (-416 742);
FORCEPROP 2 LASTPIN (-575 725) $PN 1
J 0
(-565 735);
DISPLAY 0.808511 (-565 735);
FORCEPROP 2 LASTPIN (-725 725) $PN 2
J 2
(-735 735);
DISPLAY 0.808511 (-735 735);
FORCEPROP 2 LAST TOLERANCE 20%
J 2
(-725 775);
DISPLAY 0.553191 (-725 775);
DISPLAY INVISIBLE (-725 775);
FORCEPROP 2 LAST PACK_TYPE C0201
J 2
(-825 775);
DISPLAY 0.553191 (-825 775);
DISPLAY INVISIBLE (-825 775);
FORCEPROP 1 LAST MATERIAL X6S
J 2
(-641 804);
DISPLAY 0.574468 (-641 804);
PAINT GREEN (-641 804);
DISPLAY INVISIBLE (-641 804);
FORCEPROP 2 LAST VOLTAGE 6.3V
J 2
(-1000 775);
DISPLAY 0.553191 (-1000 775);
DISPLAY INVISIBLE (-1000 775);
FORCEPROP 2 LAST CDS_LIB pure_quanta
J 2
(-650 725);
DISPLAY INVISIBLE (-650 725);
FORCEPROP 1 LAST CDS_LMAN_SYM_OUTLINE -25,50,25,-50
J 2
(-650 725);
DISPLAY 0.468085 (-650 725);
PAINT GREEN (-650 725);
DISPLAY INVISIBLE (-650 725);
FORCEPROP 1 LAST PIN_NAMES_ROTATE TRUE
J 2
(-650 725);
DISPLAY 0.489362 (-650 725);
PAINT GREEN (-650 725);
DISPLAY INVISIBLE (-650 725);
FORCEPROP 1 LAST PATH I27
J 2
(-650 725);
DISPLAY 0.723404 (-650 725);
DISPLAY INVISIBLE (-650 725);
FORCEPROP 1 LAST $LOCATION C863
J 0
(-400 800);
DISPLAY 1.021277 (-400 800);
DISPLAY INVISIBLE (-400 800);
FORCEPROP 2 LAST CDS_LOCATION C863
J 0
(-400 800);
DISPLAY 1.021277 (-400 800);
DISPLAY INVISIBLE (-400 800);
FORCEPROP 2 LAST $SEC 1
J 2
(-475 800);
DISPLAY 0.680851 (-475 800);
PAINT MONO (-475 800);
DISPLAY INVISIBLE (-475 800);
FORCEPROP 2 LAST CDS_SEC 1
J 2
(-475 800);
DISPLAY 0.680851 (-475 800);
DISPLAY INVISIBLE (-475 800);
FORCEADD Q_CAP_DIFFBUS..2
R 2
(-650 775);
FORCEPROP 1 LAST PART_NUMBER SP_CH4221MEE01
J 2
(-766 863);
DISPLAY 0.574468 (-766 863);
PAINT GREEN (-766 863);
DISPLAY INVISIBLE (-766 863);
FORCEPROP 2 LAST VALUE DIFF BUS_0.22UF
J 2
(-800 775);
DISPLAY 0.553191 (-800 775);
FORCEPROP 1 LAST $LOCATION C862
J 2
(-416 792);
DISPLAY 0.723404 (-416 792);
PAINT GREEN (-416 792);
FORCEPROP 2 LASTPIN (-575 775) $PN 1
J 0
(-565 785);
DISPLAY 0.808511 (-565 785);
FORCEPROP 2 LASTPIN (-725 775) $PN 2
J 2
(-735 785);
DISPLAY 0.808511 (-735 785);
FORCEPROP 2 LAST TOLERANCE 20%
J 2
(-725 825);
DISPLAY 0.553191 (-725 825);
DISPLAY INVISIBLE (-725 825);
FORCEPROP 2 LAST PACK_TYPE C0201
J 2
(-825 825);
DISPLAY 0.553191 (-825 825);
DISPLAY INVISIBLE (-825 825);
FORCEPROP 1 LAST MATERIAL X6S
J 2
(-641 854);
DISPLAY 0.574468 (-641 854);
PAINT GREEN (-641 854);
DISPLAY INVISIBLE (-641 854);
FORCEPROP 2 LAST VOLTAGE 6.3V
J 2
(-1000 825);
DISPLAY 0.553191 (-1000 825);
DISPLAY INVISIBLE (-1000 825);
FORCEPROP 2 LAST CDS_LIB pure_quanta
J 2
(-650 775);
DISPLAY INVISIBLE (-650 775);
FORCEPROP 1 LAST CDS_LMAN_SYM_OUTLINE -25,50,25,-50
J 2
(-650 775);
DISPLAY 0.468085 (-650 775);
PAINT GREEN (-650 775);
DISPLAY INVISIBLE (-650 775);
FORCEPROP 1 LAST PIN_NAMES_ROTATE TRUE
J 2
(-650 775);
DISPLAY 0.489362 (-650 775);
PAINT GREEN (-650 775);
DISPLAY INVISIBLE (-650 775);
FORCEPROP 1 LAST PATH I28
J 2
(-650 775);
DISPLAY 0.723404 (-650 775);
DISPLAY INVISIBLE (-650 775);
FORCEPROP 1 LAST $LOCATION C862
J 0
(-400 850);
DISPLAY 1.021277 (-400 850);
DISPLAY INVISIBLE (-400 850);
FORCEPROP 2 LAST CDS_LOCATION C862
J 0
(-400 850);
DISPLAY 1.021277 (-400 850);
DISPLAY INVISIBLE (-400 850);
FORCEPROP 2 LAST $SEC 1
J 2
(-475 850);
DISPLAY 0.680851 (-475 850);
PAINT MONO (-475 850);
DISPLAY INVISIBLE (-475 850);
FORCEPROP 2 LAST CDS_SEC 1
J 2
(-475 850);
DISPLAY 0.680851 (-475 850);
DISPLAY INVISIBLE (-475 850);
FORCEADD Q_CAP_DIFFBUS..2
R 2
(-650 925);
FORCEPROP 1 LAST PART_NUMBER SP_CH4221MEE01
J 2
(-766 1013);
DISPLAY 0.574468 (-766 1013);
PAINT GREEN (-766 1013);
DISPLAY INVISIBLE (-766 1013);
FORCEPROP 2 LAST VALUE DIFF BUS_0.22UF
J 2
(-800 925);
DISPLAY 0.553191 (-800 925);
FORCEPROP 1 LAST $LOCATION C861
J 2
(-416 942);
DISPLAY 0.723404 (-416 942);
PAINT GREEN (-416 942);
FORCEPROP 2 LASTPIN (-575 925) $PN 1
J 0
(-565 935);
DISPLAY 0.808511 (-565 935);
FORCEPROP 2 LASTPIN (-725 925) $PN 2
J 2
(-735 935);
DISPLAY 0.808511 (-735 935);
FORCEPROP 2 LAST TOLERANCE 20%
J 2
(-725 975);
DISPLAY 0.553191 (-725 975);
DISPLAY INVISIBLE (-725 975);
FORCEPROP 2 LAST PACK_TYPE C0201
J 2
(-825 975);
DISPLAY 0.553191 (-825 975);
DISPLAY INVISIBLE (-825 975);
FORCEPROP 1 LAST MATERIAL X6S
J 2
(-641 1004);
DISPLAY 0.574468 (-641 1004);
PAINT GREEN (-641 1004);
DISPLAY INVISIBLE (-641 1004);
FORCEPROP 2 LAST VOLTAGE 6.3V
J 2
(-1000 975);
DISPLAY 0.553191 (-1000 975);
DISPLAY INVISIBLE (-1000 975);
FORCEPROP 1 LAST CDS_LMAN_SYM_OUTLINE -25,50,25,-50
J 2
(-650 925);
DISPLAY 0.468085 (-650 925);
PAINT GREEN (-650 925);
DISPLAY INVISIBLE (-650 925);
FORCEPROP 2 LAST CDS_LIB pure_quanta
J 2
(-650 925);
DISPLAY INVISIBLE (-650 925);
FORCEPROP 1 LAST PIN_NAMES_ROTATE TRUE
J 2
(-650 925);
DISPLAY 0.489362 (-650 925);
PAINT GREEN (-650 925);
DISPLAY INVISIBLE (-650 925);
FORCEPROP 1 LAST PATH I29
J 2
(-650 925);
DISPLAY 0.723404 (-650 925);
DISPLAY INVISIBLE (-650 925);
FORCEPROP 1 LAST $LOCATION C861
J 0
(-400 1000);
DISPLAY 1.021277 (-400 1000);
DISPLAY INVISIBLE (-400 1000);
FORCEPROP 2 LAST CDS_LOCATION C861
J 0
(-400 1000);
DISPLAY 1.021277 (-400 1000);
DISPLAY INVISIBLE (-400 1000);
FORCEPROP 2 LAST $SEC 1
J 2
(-475 1000);
DISPLAY 0.680851 (-475 1000);
PAINT MONO (-475 1000);
DISPLAY INVISIBLE (-475 1000);
FORCEPROP 2 LAST CDS_SEC 1
J 2
(-475 1000);
DISPLAY 0.680851 (-475 1000);
DISPLAY INVISIBLE (-475 1000);
FORCEADD OFFPAGE..1
(-2575 3575);
FORCEPROP 2 LAST $XR0 29 
J 0
(-2796 3575);
DISPLAY 0.638298 (-2796 3575);
PAINT MONO (-2796 3575);
FORCEPROP 2 LAST CDS_LIB standard
J 0
(-2575 3575);
DISPLAY INVISIBLE (-2575 3575);
FORCEPROP 1 LAST OFFPAGE TRUE
J 0
(-2250 3450);
DISPLAY 0.872340 (-2250 3450);
DISPLAY INVISIBLE (-2250 3450);
FORCEPROP 1 LAST COMMENT_BODY TRUE
J 0
(-2450 3475);
DISPLAY 0.872340 (-2450 3475);
PAINT GREEN (-2450 3475);
DISPLAY INVISIBLE (-2450 3475);
FORCEPROP 2 LAST PATH I3
J 0
(-2825 3625);
DISPLAY 1.021277 (-2825 3625);
DISPLAY INVISIBLE (-2825 3625);
FORCEADD Q_CAP_DIFFBUS..2
R 2
(-650 975);
FORCEPROP 1 LAST PART_NUMBER SP_CH4221MEE01
J 2
(-766 1063);
DISPLAY 0.574468 (-766 1063);
PAINT GREEN (-766 1063);
DISPLAY INVISIBLE (-766 1063);
FORCEPROP 2 LAST VALUE DIFF BUS_0.22UF
J 2
(-800 975);
DISPLAY 0.553191 (-800 975);
FORCEPROP 1 LAST $LOCATION C860
J 2
(-416 992);
DISPLAY 0.723404 (-416 992);
PAINT GREEN (-416 992);
FORCEPROP 2 LASTPIN (-575 975) $PN 1
J 0
(-565 985);
DISPLAY 0.808511 (-565 985);
FORCEPROP 2 LASTPIN (-725 975) $PN 2
J 2
(-735 985);
DISPLAY 0.808511 (-735 985);
FORCEPROP 2 LAST TOLERANCE 20%
J 2
(-725 1025);
DISPLAY 0.553191 (-725 1025);
DISPLAY INVISIBLE (-725 1025);
FORCEPROP 2 LAST PACK_TYPE C0201
J 2
(-825 1025);
DISPLAY 0.553191 (-825 1025);
DISPLAY INVISIBLE (-825 1025);
FORCEPROP 1 LAST MATERIAL X6S
J 2
(-641 1054);
DISPLAY 0.574468 (-641 1054);
PAINT GREEN (-641 1054);
DISPLAY INVISIBLE (-641 1054);
FORCEPROP 2 LAST VOLTAGE 6.3V
J 2
(-1000 1025);
DISPLAY 0.553191 (-1000 1025);
DISPLAY INVISIBLE (-1000 1025);
FORCEPROP 1 LAST CDS_LMAN_SYM_OUTLINE -25,50,25,-50
J 2
(-650 975);
DISPLAY 0.468085 (-650 975);
PAINT GREEN (-650 975);
DISPLAY INVISIBLE (-650 975);
FORCEPROP 2 LAST CDS_LIB pure_quanta
J 2
(-650 975);
DISPLAY INVISIBLE (-650 975);
FORCEPROP 1 LAST PIN_NAMES_ROTATE TRUE
J 2
(-650 975);
DISPLAY 0.489362 (-650 975);
PAINT GREEN (-650 975);
DISPLAY INVISIBLE (-650 975);
FORCEPROP 1 LAST PATH I30
J 2
(-650 975);
DISPLAY 0.723404 (-650 975);
DISPLAY INVISIBLE (-650 975);
FORCEPROP 1 LAST $LOCATION C860
J 0
(-400 1050);
DISPLAY 1.021277 (-400 1050);
DISPLAY INVISIBLE (-400 1050);
FORCEPROP 2 LAST CDS_LOCATION C860
J 0
(-400 1050);
DISPLAY 1.021277 (-400 1050);
DISPLAY INVISIBLE (-400 1050);
FORCEPROP 2 LAST $SEC 1
J 2
(-475 1050);
DISPLAY 0.680851 (-475 1050);
PAINT MONO (-475 1050);
DISPLAY INVISIBLE (-475 1050);
FORCEPROP 2 LAST CDS_SEC 1
J 2
(-475 1050);
DISPLAY 0.680851 (-475 1050);
DISPLAY INVISIBLE (-475 1050);
FORCEADD TAP..1
(-100 175);
FORCEPROP 3 LASTPIN (-150 175) SIG_NAME P5E_CPU0_PE1_TX_C_DN<0>
J 0
(-140 185);
DISPLAY 0.659574 (-140 185);
PAINT MONO (-140 185);
DISPLAY INVISIBLE (-140 185);
FORCEPROP 1 LASTPIN (-150 175) BN 0
J 0
(-162 183);
DISPLAY 0.680851 (-162 183);
PAINT GREEN (-162 183);
FORCEPROP 2 LAST CDS_LIB standard
J 0
(-100 175);
DISPLAY INVISIBLE (-100 175);
FORCEPROP 1 LAST BODY_TYPE PLUMBING
J 0
(-100 225);
DISPLAY 0.872340 (-100 225);
PAINT GREEN (-100 225);
DISPLAY INVISIBLE (-100 225);
FORCEPROP 1 LAST HDL_TAP TRUE
J 0
(225 50);
DISPLAY 0.872340 (225 50);
DISPLAY INVISIBLE (225 50);
FORCEPROP 1 LAST PATH I31
J 0
(-102 175);
DISPLAY 0.872340 (-102 175);
PAINT GREEN (-102 175);
DISPLAY INVISIBLE (-102 175);
FORCEADD TAP..1
(-100 375);
FORCEPROP 3 LASTPIN (-150 375) SIG_NAME P5E_CPU0_PE1_TX_C_DN<1>
J 0
(-140 385);
DISPLAY 0.659574 (-140 385);
PAINT MONO (-140 385);
DISPLAY INVISIBLE (-140 385);
FORCEPROP 1 LASTPIN (-150 375) BN 1
J 0
(-162 383);
DISPLAY 0.680851 (-162 383);
PAINT GREEN (-162 383);
FORCEPROP 2 LAST CDS_LIB standard
J 0
(-100 375);
DISPLAY INVISIBLE (-100 375);
FORCEPROP 1 LAST BODY_TYPE PLUMBING
J 0
(-100 425);
DISPLAY 0.872340 (-100 425);
PAINT GREEN (-100 425);
DISPLAY INVISIBLE (-100 425);
FORCEPROP 1 LAST HDL_TAP TRUE
J 0
(225 250);
DISPLAY 0.872340 (225 250);
DISPLAY INVISIBLE (225 250);
FORCEPROP 1 LAST PATH I32
J 0
(-102 375);
DISPLAY 0.872340 (-102 375);
PAINT GREEN (-102 375);
DISPLAY INVISIBLE (-102 375);
FORCEADD TAP..1
(-100 575);
FORCEPROP 3 LASTPIN (-150 575) SIG_NAME P5E_CPU0_PE1_TX_C_DN<2>
J 0
(-140 585);
DISPLAY 0.659574 (-140 585);
PAINT MONO (-140 585);
DISPLAY INVISIBLE (-140 585);
FORCEPROP 1 LASTPIN (-150 575) BN 2
J 0
(-162 583);
DISPLAY 0.680851 (-162 583);
PAINT GREEN (-162 583);
FORCEPROP 2 LAST CDS_LIB standard
J 0
(-100 575);
DISPLAY INVISIBLE (-100 575);
FORCEPROP 1 LAST BODY_TYPE PLUMBING
J 0
(-100 625);
DISPLAY 0.872340 (-100 625);
PAINT GREEN (-100 625);
DISPLAY INVISIBLE (-100 625);
FORCEPROP 1 LAST HDL_TAP TRUE
J 0
(225 450);
DISPLAY 0.872340 (225 450);
DISPLAY INVISIBLE (225 450);
FORCEPROP 1 LAST PATH I33
J 0
(-102 575);
DISPLAY 0.872340 (-102 575);
PAINT GREEN (-102 575);
DISPLAY INVISIBLE (-102 575);
FORCEADD TAP..1
(-100 775);
FORCEPROP 3 LASTPIN (-150 775) SIG_NAME P5E_CPU0_PE1_TX_C_DN<3>
J 0
(-140 785);
DISPLAY 0.659574 (-140 785);
PAINT MONO (-140 785);
DISPLAY INVISIBLE (-140 785);
FORCEPROP 1 LASTPIN (-150 775) BN 3
J 0
(-162 783);
DISPLAY 0.680851 (-162 783);
PAINT GREEN (-162 783);
FORCEPROP 2 LAST CDS_LIB standard
J 0
(-100 775);
DISPLAY INVISIBLE (-100 775);
FORCEPROP 1 LAST BODY_TYPE PLUMBING
J 0
(-100 825);
DISPLAY 0.872340 (-100 825);
PAINT GREEN (-100 825);
DISPLAY INVISIBLE (-100 825);
FORCEPROP 1 LAST HDL_TAP TRUE
J 0
(225 650);
DISPLAY 0.872340 (225 650);
DISPLAY INVISIBLE (225 650);
FORCEPROP 1 LAST PATH I34
J 0
(-102 775);
DISPLAY 0.872340 (-102 775);
PAINT GREEN (-102 775);
DISPLAY INVISIBLE (-102 775);
FORCEADD TAP..1
(-100 975);
FORCEPROP 3 LASTPIN (-150 975) SIG_NAME P5E_CPU0_PE1_TX_C_DN<4>
J 0
(-140 985);
DISPLAY 0.659574 (-140 985);
PAINT MONO (-140 985);
DISPLAY INVISIBLE (-140 985);
FORCEPROP 1 LASTPIN (-150 975) BN 4
J 0
(-162 983);
DISPLAY 0.680851 (-162 983);
PAINT GREEN (-162 983);
FORCEPROP 2 LAST CDS_LIB standard
J 0
(-100 975);
DISPLAY INVISIBLE (-100 975);
FORCEPROP 1 LAST BODY_TYPE PLUMBING
J 0
(-100 1025);
DISPLAY 0.872340 (-100 1025);
PAINT GREEN (-100 1025);
DISPLAY INVISIBLE (-100 1025);
FORCEPROP 1 LAST HDL_TAP TRUE
J 0
(225 850);
DISPLAY 0.872340 (225 850);
DISPLAY INVISIBLE (225 850);
FORCEPROP 1 LAST PATH I35
J 0
(-102 975);
DISPLAY 0.872340 (-102 975);
PAINT GREEN (-102 975);
DISPLAY INVISIBLE (-102 975);
FORCEADD Q_CAP_DIFFBUS..2
R 2
(-650 1125);
FORCEPROP 1 LAST PART_NUMBER SP_CH4221MEE01
J 2
(-766 1213);
DISPLAY 0.574468 (-766 1213);
PAINT GREEN (-766 1213);
DISPLAY INVISIBLE (-766 1213);
FORCEPROP 2 LAST VALUE DIFF BUS_0.22UF
J 2
(-800 1125);
DISPLAY 0.553191 (-800 1125);
FORCEPROP 1 LAST $LOCATION C859
J 2
(-416 1142);
DISPLAY 0.723404 (-416 1142);
PAINT GREEN (-416 1142);
FORCEPROP 2 LASTPIN (-575 1125) $PN 1
J 0
(-565 1135);
DISPLAY 0.808511 (-565 1135);
FORCEPROP 2 LASTPIN (-725 1125) $PN 2
J 2
(-735 1135);
DISPLAY 0.808511 (-735 1135);
FORCEPROP 2 LAST TOLERANCE 20%
J 2
(-725 1175);
DISPLAY 0.553191 (-725 1175);
DISPLAY INVISIBLE (-725 1175);
FORCEPROP 2 LAST PACK_TYPE C0201
J 2
(-825 1175);
DISPLAY 0.553191 (-825 1175);
DISPLAY INVISIBLE (-825 1175);
FORCEPROP 1 LAST MATERIAL X6S
J 2
(-641 1204);
DISPLAY 0.574468 (-641 1204);
PAINT GREEN (-641 1204);
DISPLAY INVISIBLE (-641 1204);
FORCEPROP 2 LAST VOLTAGE 6.3V
J 2
(-1000 1175);
DISPLAY 0.553191 (-1000 1175);
DISPLAY INVISIBLE (-1000 1175);
FORCEPROP 1 LAST CDS_LMAN_SYM_OUTLINE -25,50,25,-50
J 2
(-650 1125);
DISPLAY 0.468085 (-650 1125);
PAINT GREEN (-650 1125);
DISPLAY INVISIBLE (-650 1125);
FORCEPROP 2 LAST CDS_LIB pure_quanta
J 2
(-650 1125);
DISPLAY INVISIBLE (-650 1125);
FORCEPROP 1 LAST PIN_NAMES_ROTATE TRUE
J 2
(-650 1125);
DISPLAY 0.489362 (-650 1125);
PAINT GREEN (-650 1125);
DISPLAY INVISIBLE (-650 1125);
FORCEPROP 1 LAST PATH I36
J 2
(-650 1125);
DISPLAY 0.723404 (-650 1125);
DISPLAY INVISIBLE (-650 1125);
FORCEPROP 1 LAST $LOCATION C859
J 0
(-400 1200);
DISPLAY 1.021277 (-400 1200);
DISPLAY INVISIBLE (-400 1200);
FORCEPROP 2 LAST CDS_LOCATION C859
J 0
(-400 1200);
DISPLAY 1.021277 (-400 1200);
DISPLAY INVISIBLE (-400 1200);
FORCEPROP 2 LAST $SEC 1
J 2
(-475 1200);
DISPLAY 0.680851 (-475 1200);
PAINT MONO (-475 1200);
DISPLAY INVISIBLE (-475 1200);
FORCEPROP 2 LAST CDS_SEC 1
J 2
(-475 1200);
DISPLAY 0.680851 (-475 1200);
DISPLAY INVISIBLE (-475 1200);
FORCEADD Q_CAP_DIFFBUS..2
R 2
(-650 1175);
FORCEPROP 1 LAST PART_NUMBER SP_CH4221MEE01
J 2
(-766 1263);
DISPLAY 0.574468 (-766 1263);
PAINT GREEN (-766 1263);
DISPLAY INVISIBLE (-766 1263);
FORCEPROP 2 LAST VALUE DIFF BUS_0.22UF
J 2
(-800 1175);
DISPLAY 0.553191 (-800 1175);
FORCEPROP 1 LAST $LOCATION C858
J 2
(-416 1192);
DISPLAY 0.723404 (-416 1192);
PAINT GREEN (-416 1192);
FORCEPROP 2 LASTPIN (-575 1175) $PN 1
J 0
(-565 1185);
DISPLAY 0.808511 (-565 1185);
FORCEPROP 2 LASTPIN (-725 1175) $PN 2
J 2
(-735 1185);
DISPLAY 0.808511 (-735 1185);
FORCEPROP 2 LAST TOLERANCE 20%
J 2
(-725 1225);
DISPLAY 0.553191 (-725 1225);
DISPLAY INVISIBLE (-725 1225);
FORCEPROP 2 LAST PACK_TYPE C0201
J 2
(-825 1225);
DISPLAY 0.553191 (-825 1225);
DISPLAY INVISIBLE (-825 1225);
FORCEPROP 1 LAST MATERIAL X6S
J 2
(-641 1254);
DISPLAY 0.574468 (-641 1254);
PAINT GREEN (-641 1254);
DISPLAY INVISIBLE (-641 1254);
FORCEPROP 2 LAST VOLTAGE 6.3V
J 2
(-1000 1225);
DISPLAY 0.553191 (-1000 1225);
DISPLAY INVISIBLE (-1000 1225);
FORCEPROP 1 LAST CDS_LMAN_SYM_OUTLINE -25,50,25,-50
J 2
(-650 1175);
DISPLAY 0.468085 (-650 1175);
PAINT GREEN (-650 1175);
DISPLAY INVISIBLE (-650 1175);
FORCEPROP 2 LAST CDS_LIB pure_quanta
J 2
(-650 1175);
DISPLAY INVISIBLE (-650 1175);
FORCEPROP 1 LAST PIN_NAMES_ROTATE TRUE
J 2
(-650 1175);
DISPLAY 0.489362 (-650 1175);
PAINT GREEN (-650 1175);
DISPLAY INVISIBLE (-650 1175);
FORCEPROP 1 LAST PATH I37
J 2
(-650 1175);
DISPLAY 0.723404 (-650 1175);
DISPLAY INVISIBLE (-650 1175);
FORCEPROP 1 LAST $LOCATION C858
J 0
(-400 1250);
DISPLAY 1.021277 (-400 1250);
DISPLAY INVISIBLE (-400 1250);
FORCEPROP 2 LAST CDS_LOCATION C858
J 0
(-400 1250);
DISPLAY 1.021277 (-400 1250);
DISPLAY INVISIBLE (-400 1250);
FORCEPROP 2 LAST $SEC 1
J 2
(-475 1250);
DISPLAY 0.680851 (-475 1250);
PAINT MONO (-475 1250);
DISPLAY INVISIBLE (-475 1250);
FORCEPROP 2 LAST CDS_SEC 1
J 2
(-475 1250);
DISPLAY 0.680851 (-475 1250);
DISPLAY INVISIBLE (-475 1250);
FORCEADD Q_CAP_DIFFBUS..2
R 2
(-650 1325);
FORCEPROP 1 LAST PART_NUMBER SP_CH4221MEE01
J 2
(-766 1413);
DISPLAY 0.574468 (-766 1413);
PAINT GREEN (-766 1413);
DISPLAY INVISIBLE (-766 1413);
FORCEPROP 2 LAST VALUE DIFF BUS_0.22UF
J 2
(-800 1325);
DISPLAY 0.553191 (-800 1325);
FORCEPROP 1 LAST $LOCATION C857
J 2
(-416 1342);
DISPLAY 0.723404 (-416 1342);
PAINT GREEN (-416 1342);
FORCEPROP 2 LASTPIN (-575 1325) $PN 1
J 0
(-565 1335);
DISPLAY 0.808511 (-565 1335);
FORCEPROP 2 LASTPIN (-725 1325) $PN 2
J 2
(-735 1335);
DISPLAY 0.808511 (-735 1335);
FORCEPROP 2 LAST TOLERANCE 20%
J 2
(-725 1375);
DISPLAY 0.553191 (-725 1375);
DISPLAY INVISIBLE (-725 1375);
FORCEPROP 2 LAST PACK_TYPE C0201
J 2
(-825 1375);
DISPLAY 0.553191 (-825 1375);
DISPLAY INVISIBLE (-825 1375);
FORCEPROP 1 LAST MATERIAL X6S
J 2
(-641 1404);
DISPLAY 0.574468 (-641 1404);
PAINT GREEN (-641 1404);
DISPLAY INVISIBLE (-641 1404);
FORCEPROP 2 LAST VOLTAGE 6.3V
J 2
(-1000 1375);
DISPLAY 0.553191 (-1000 1375);
DISPLAY INVISIBLE (-1000 1375);
FORCEPROP 1 LAST CDS_LMAN_SYM_OUTLINE -25,50,25,-50
J 2
(-650 1325);
DISPLAY 0.468085 (-650 1325);
PAINT GREEN (-650 1325);
DISPLAY INVISIBLE (-650 1325);
FORCEPROP 2 LAST CDS_LIB pure_quanta
J 2
(-650 1325);
DISPLAY INVISIBLE (-650 1325);
FORCEPROP 1 LAST PIN_NAMES_ROTATE TRUE
J 2
(-650 1325);
DISPLAY 0.489362 (-650 1325);
PAINT GREEN (-650 1325);
DISPLAY INVISIBLE (-650 1325);
FORCEPROP 1 LAST PATH I38
J 2
(-650 1325);
DISPLAY 0.723404 (-650 1325);
DISPLAY INVISIBLE (-650 1325);
FORCEPROP 1 LAST $LOCATION C857
J 0
(-400 1400);
DISPLAY 1.021277 (-400 1400);
DISPLAY INVISIBLE (-400 1400);
FORCEPROP 2 LAST CDS_LOCATION C857
J 0
(-400 1400);
DISPLAY 1.021277 (-400 1400);
DISPLAY INVISIBLE (-400 1400);
FORCEPROP 2 LAST $SEC 1
J 2
(-475 1400);
DISPLAY 0.680851 (-475 1400);
PAINT MONO (-475 1400);
DISPLAY INVISIBLE (-475 1400);
FORCEPROP 2 LAST CDS_SEC 1
J 2
(-475 1400);
DISPLAY 0.680851 (-475 1400);
DISPLAY INVISIBLE (-475 1400);
FORCEADD Q_CAP_DIFFBUS..2
R 2
(-650 1375);
FORCEPROP 1 LAST PART_NUMBER SP_CH4221MEE01
J 2
(-766 1463);
DISPLAY 0.574468 (-766 1463);
PAINT GREEN (-766 1463);
DISPLAY INVISIBLE (-766 1463);
FORCEPROP 2 LAST VALUE DIFF BUS_0.22UF
J 2
(-800 1375);
DISPLAY 0.553191 (-800 1375);
FORCEPROP 1 LAST $LOCATION C856
J 2
(-416 1392);
DISPLAY 0.723404 (-416 1392);
PAINT GREEN (-416 1392);
FORCEPROP 2 LASTPIN (-575 1375) $PN 1
J 0
(-565 1385);
DISPLAY 0.808511 (-565 1385);
FORCEPROP 2 LASTPIN (-725 1375) $PN 2
J 2
(-735 1385);
DISPLAY 0.808511 (-735 1385);
FORCEPROP 2 LAST TOLERANCE 20%
J 2
(-725 1425);
DISPLAY 0.553191 (-725 1425);
DISPLAY INVISIBLE (-725 1425);
FORCEPROP 2 LAST PACK_TYPE C0201
J 2
(-825 1425);
DISPLAY 0.553191 (-825 1425);
DISPLAY INVISIBLE (-825 1425);
FORCEPROP 1 LAST MATERIAL X6S
J 2
(-641 1454);
DISPLAY 0.574468 (-641 1454);
PAINT GREEN (-641 1454);
DISPLAY INVISIBLE (-641 1454);
FORCEPROP 2 LAST VOLTAGE 6.3V
J 2
(-1000 1425);
DISPLAY 0.553191 (-1000 1425);
DISPLAY INVISIBLE (-1000 1425);
FORCEPROP 1 LAST CDS_LMAN_SYM_OUTLINE -25,50,25,-50
J 2
(-650 1375);
DISPLAY 0.468085 (-650 1375);
PAINT GREEN (-650 1375);
DISPLAY INVISIBLE (-650 1375);
FORCEPROP 2 LAST CDS_LIB pure_quanta
J 2
(-650 1375);
DISPLAY INVISIBLE (-650 1375);
FORCEPROP 1 LAST PIN_NAMES_ROTATE TRUE
J 2
(-650 1375);
DISPLAY 0.489362 (-650 1375);
PAINT GREEN (-650 1375);
DISPLAY INVISIBLE (-650 1375);
FORCEPROP 1 LAST PATH I39
J 2
(-650 1375);
DISPLAY 0.723404 (-650 1375);
DISPLAY INVISIBLE (-650 1375);
FORCEPROP 1 LAST $LOCATION C856
J 0
(-400 1450);
DISPLAY 1.021277 (-400 1450);
DISPLAY INVISIBLE (-400 1450);
FORCEPROP 2 LAST CDS_LOCATION C856
J 0
(-400 1450);
DISPLAY 1.021277 (-400 1450);
DISPLAY INVISIBLE (-400 1450);
FORCEPROP 2 LAST $SEC 1
J 2
(-475 1450);
DISPLAY 0.680851 (-475 1450);
PAINT MONO (-475 1450);
DISPLAY INVISIBLE (-475 1450);
FORCEPROP 2 LAST CDS_SEC 1
J 2
(-475 1450);
DISPLAY 0.680851 (-475 1450);
DISPLAY INVISIBLE (-475 1450);
FORCEADD OFFPAGE..1
(-2575 3525);
FORCEPROP 2 LAST $XR0 29 
J 0
(-2796 3525);
DISPLAY 0.638298 (-2796 3525);
PAINT MONO (-2796 3525);
FORCEPROP 2 LAST CDS_LIB standard
J 0
(-2575 3525);
DISPLAY INVISIBLE (-2575 3525);
FORCEPROP 1 LAST OFFPAGE TRUE
J 0
(-2250 3400);
DISPLAY 0.872340 (-2250 3400);
DISPLAY INVISIBLE (-2250 3400);
FORCEPROP 1 LAST COMMENT_BODY TRUE
J 0
(-2450 3425);
DISPLAY 0.872340 (-2450 3425);
PAINT GREEN (-2450 3425);
DISPLAY INVISIBLE (-2450 3425);
FORCEPROP 2 LAST PATH I4
J 0
(-2825 3575);
DISPLAY 1.021277 (-2825 3575);
DISPLAY INVISIBLE (-2825 3575);
FORCEADD Q_CAP_DIFFBUS..2
R 2
(-650 1525);
FORCEPROP 1 LAST PART_NUMBER SP_CH4221MEE01
J 2
(-766 1613);
DISPLAY 0.574468 (-766 1613);
PAINT GREEN (-766 1613);
DISPLAY INVISIBLE (-766 1613);
FORCEPROP 2 LAST VALUE DIFF BUS_0.22UF
J 2
(-800 1525);
DISPLAY 0.553191 (-800 1525);
FORCEPROP 1 LAST $LOCATION C855
J 2
(-416 1542);
DISPLAY 0.723404 (-416 1542);
PAINT GREEN (-416 1542);
FORCEPROP 2 LASTPIN (-575 1525) $PN 1
J 0
(-565 1535);
DISPLAY 0.808511 (-565 1535);
FORCEPROP 2 LASTPIN (-725 1525) $PN 2
J 2
(-735 1535);
DISPLAY 0.808511 (-735 1535);
FORCEPROP 2 LAST TOLERANCE 20%
J 2
(-725 1575);
DISPLAY 0.553191 (-725 1575);
DISPLAY INVISIBLE (-725 1575);
FORCEPROP 2 LAST PACK_TYPE C0201
J 2
(-825 1575);
DISPLAY 0.553191 (-825 1575);
DISPLAY INVISIBLE (-825 1575);
FORCEPROP 1 LAST MATERIAL X6S
J 2
(-641 1604);
DISPLAY 0.574468 (-641 1604);
PAINT GREEN (-641 1604);
DISPLAY INVISIBLE (-641 1604);
FORCEPROP 2 LAST VOLTAGE 6.3V
J 2
(-1000 1575);
DISPLAY 0.553191 (-1000 1575);
DISPLAY INVISIBLE (-1000 1575);
FORCEPROP 1 LAST CDS_LMAN_SYM_OUTLINE -25,50,25,-50
J 2
(-650 1525);
DISPLAY 0.468085 (-650 1525);
PAINT GREEN (-650 1525);
DISPLAY INVISIBLE (-650 1525);
FORCEPROP 2 LAST CDS_LIB pure_quanta
J 2
(-650 1525);
DISPLAY INVISIBLE (-650 1525);
FORCEPROP 1 LAST PIN_NAMES_ROTATE TRUE
J 2
(-650 1525);
DISPLAY 0.489362 (-650 1525);
PAINT GREEN (-650 1525);
DISPLAY INVISIBLE (-650 1525);
FORCEPROP 1 LAST PATH I40
J 2
(-650 1525);
DISPLAY 0.723404 (-650 1525);
DISPLAY INVISIBLE (-650 1525);
FORCEPROP 1 LAST $LOCATION C855
J 0
(-400 1600);
DISPLAY 1.021277 (-400 1600);
DISPLAY INVISIBLE (-400 1600);
FORCEPROP 2 LAST CDS_LOCATION C855
J 0
(-400 1600);
DISPLAY 1.021277 (-400 1600);
DISPLAY INVISIBLE (-400 1600);
FORCEPROP 2 LAST $SEC 1
J 2
(-475 1600);
DISPLAY 0.680851 (-475 1600);
PAINT MONO (-475 1600);
DISPLAY INVISIBLE (-475 1600);
FORCEPROP 2 LAST CDS_SEC 1
J 2
(-475 1600);
DISPLAY 0.680851 (-475 1600);
DISPLAY INVISIBLE (-475 1600);
FORCEADD Q_CAP_DIFFBUS..2
R 2
(-650 1575);
FORCEPROP 1 LAST PART_NUMBER SP_CH4221MEE01
J 2
(-766 1663);
DISPLAY 0.574468 (-766 1663);
PAINT GREEN (-766 1663);
DISPLAY INVISIBLE (-766 1663);
FORCEPROP 2 LAST VALUE DIFF BUS_0.22UF
J 2
(-800 1575);
DISPLAY 0.553191 (-800 1575);
FORCEPROP 1 LAST $LOCATION C854
J 2
(-416 1592);
DISPLAY 0.723404 (-416 1592);
PAINT GREEN (-416 1592);
FORCEPROP 2 LASTPIN (-575 1575) $PN 1
J 0
(-565 1585);
DISPLAY 0.808511 (-565 1585);
FORCEPROP 2 LASTPIN (-725 1575) $PN 2
J 2
(-735 1585);
DISPLAY 0.808511 (-735 1585);
FORCEPROP 2 LAST TOLERANCE 20%
J 2
(-725 1625);
DISPLAY 0.553191 (-725 1625);
DISPLAY INVISIBLE (-725 1625);
FORCEPROP 2 LAST PACK_TYPE C0201
J 2
(-825 1625);
DISPLAY 0.553191 (-825 1625);
DISPLAY INVISIBLE (-825 1625);
FORCEPROP 1 LAST MATERIAL X6S
J 2
(-641 1654);
DISPLAY 0.574468 (-641 1654);
PAINT GREEN (-641 1654);
DISPLAY INVISIBLE (-641 1654);
FORCEPROP 2 LAST VOLTAGE 6.3V
J 2
(-1000 1625);
DISPLAY 0.553191 (-1000 1625);
DISPLAY INVISIBLE (-1000 1625);
FORCEPROP 2 LAST CDS_LIB pure_quanta
J 2
(-650 1575);
DISPLAY INVISIBLE (-650 1575);
FORCEPROP 1 LAST CDS_LMAN_SYM_OUTLINE -25,50,25,-50
J 2
(-650 1575);
DISPLAY 0.468085 (-650 1575);
PAINT GREEN (-650 1575);
DISPLAY INVISIBLE (-650 1575);
FORCEPROP 1 LAST PIN_NAMES_ROTATE TRUE
J 2
(-650 1575);
DISPLAY 0.489362 (-650 1575);
PAINT GREEN (-650 1575);
DISPLAY INVISIBLE (-650 1575);
FORCEPROP 1 LAST PATH I41
J 2
(-650 1575);
DISPLAY 0.723404 (-650 1575);
DISPLAY INVISIBLE (-650 1575);
FORCEPROP 1 LAST $LOCATION C854
J 0
(-400 1650);
DISPLAY 1.021277 (-400 1650);
DISPLAY INVISIBLE (-400 1650);
FORCEPROP 2 LAST CDS_LOCATION C854
J 0
(-400 1650);
DISPLAY 1.021277 (-400 1650);
DISPLAY INVISIBLE (-400 1650);
FORCEPROP 2 LAST $SEC 1
J 2
(-475 1650);
DISPLAY 0.680851 (-475 1650);
PAINT MONO (-475 1650);
DISPLAY INVISIBLE (-475 1650);
FORCEPROP 2 LAST CDS_SEC 1
J 2
(-475 1650);
DISPLAY 0.680851 (-475 1650);
DISPLAY INVISIBLE (-475 1650);
FORCEADD TAP..1
(-100 1375);
FORCEPROP 3 LASTPIN (-150 1375) SIG_NAME P5E_CPU0_PE1_TX_C_DN<6>
J 0
(-140 1385);
DISPLAY 0.659574 (-140 1385);
PAINT MONO (-140 1385);
DISPLAY INVISIBLE (-140 1385);
FORCEPROP 1 LASTPIN (-150 1375) BN 6
J 0
(-162 1383);
DISPLAY 0.680851 (-162 1383);
PAINT GREEN (-162 1383);
FORCEPROP 2 LAST CDS_LIB standard
J 0
(-100 1375);
DISPLAY INVISIBLE (-100 1375);
FORCEPROP 1 LAST BODY_TYPE PLUMBING
J 0
(-100 1425);
DISPLAY 0.872340 (-100 1425);
PAINT GREEN (-100 1425);
DISPLAY INVISIBLE (-100 1425);
FORCEPROP 1 LAST HDL_TAP TRUE
J 0
(225 1250);
DISPLAY 0.872340 (225 1250);
DISPLAY INVISIBLE (225 1250);
FORCEPROP 1 LAST PATH I42
J 0
(-102 1375);
DISPLAY 0.872340 (-102 1375);
PAINT GREEN (-102 1375);
DISPLAY INVISIBLE (-102 1375);
FORCEADD TAP..1
(-100 1175);
FORCEPROP 3 LASTPIN (-150 1175) SIG_NAME P5E_CPU0_PE1_TX_C_DN<5>
J 0
(-140 1185);
DISPLAY 0.659574 (-140 1185);
PAINT MONO (-140 1185);
DISPLAY INVISIBLE (-140 1185);
FORCEPROP 1 LASTPIN (-150 1175) BN 5
J 0
(-162 1183);
DISPLAY 0.680851 (-162 1183);
PAINT GREEN (-162 1183);
FORCEPROP 2 LAST CDS_LIB standard
J 0
(-100 1175);
DISPLAY INVISIBLE (-100 1175);
FORCEPROP 1 LAST BODY_TYPE PLUMBING
J 0
(-100 1225);
DISPLAY 0.872340 (-100 1225);
PAINT GREEN (-100 1225);
DISPLAY INVISIBLE (-100 1225);
FORCEPROP 1 LAST HDL_TAP TRUE
J 0
(225 1050);
DISPLAY 0.872340 (225 1050);
DISPLAY INVISIBLE (225 1050);
FORCEPROP 1 LAST PATH I43
J 0
(-102 1175);
DISPLAY 0.872340 (-102 1175);
PAINT GREEN (-102 1175);
DISPLAY INVISIBLE (-102 1175);
FORCEADD TAP..1
(-100 1575);
FORCEPROP 3 LASTPIN (-150 1575) SIG_NAME P5E_CPU0_PE1_TX_C_DN<7>
J 0
(-140 1585);
DISPLAY 0.659574 (-140 1585);
PAINT MONO (-140 1585);
DISPLAY INVISIBLE (-140 1585);
FORCEPROP 1 LASTPIN (-150 1575) BN 7
J 0
(-162 1583);
DISPLAY 0.680851 (-162 1583);
PAINT GREEN (-162 1583);
FORCEPROP 2 LAST CDS_LIB standard
J 0
(-100 1575);
DISPLAY INVISIBLE (-100 1575);
FORCEPROP 1 LAST BODY_TYPE PLUMBING
J 0
(-100 1625);
DISPLAY 0.872340 (-100 1625);
PAINT GREEN (-100 1625);
DISPLAY INVISIBLE (-100 1625);
FORCEPROP 1 LAST HDL_TAP TRUE
J 0
(225 1450);
DISPLAY 0.872340 (225 1450);
DISPLAY INVISIBLE (225 1450);
FORCEPROP 1 LAST PATH I44
J 0
(-102 1575);
DISPLAY 0.872340 (-102 1575);
PAINT GREEN (-102 1575);
DISPLAY INVISIBLE (-102 1575);
FORCEADD TAP..1
R 2
(-1625 2100);
FORCEPROP 3 LASTPIN (-1575 2100) SIG_NAME P5E_CPU0_PE1_TX_DP<8>
J 0
(-1565 2110);
DISPLAY 0.659574 (-1565 2110);
PAINT MONO (-1565 2110);
DISPLAY INVISIBLE (-1565 2110);
FORCEPROP 1 LASTPIN (-1575 2100) BN 8
J 2
(-1563 2108);
DISPLAY 0.680851 (-1563 2108);
PAINT GREEN (-1563 2108);
FORCEPROP 2 LAST CDS_LIB standard
J 0
(-1625 2100);
DISPLAY INVISIBLE (-1625 2100);
FORCEPROP 1 LAST BODY_TYPE PLUMBING
J 2
(-1625 2150);
DISPLAY 0.872340 (-1625 2150);
PAINT GREEN (-1625 2150);
DISPLAY INVISIBLE (-1625 2150);
FORCEPROP 1 LAST HDL_TAP TRUE
J 2
(-1950 1975);
DISPLAY 0.872340 (-1950 1975);
DISPLAY INVISIBLE (-1950 1975);
FORCEPROP 1 LAST PATH I45
J 2
(-1623 2100);
DISPLAY 0.872340 (-1623 2100);
PAINT GREEN (-1623 2100);
DISPLAY INVISIBLE (-1623 2100);
FORCEADD TAP..1
R 2
(-1625 2300);
FORCEPROP 3 LASTPIN (-1575 2300) SIG_NAME P5E_CPU0_PE1_TX_DP<9>
J 0
(-1565 2310);
DISPLAY 0.659574 (-1565 2310);
PAINT MONO (-1565 2310);
DISPLAY INVISIBLE (-1565 2310);
FORCEPROP 1 LASTPIN (-1575 2300) BN 9
J 2
(-1563 2308);
DISPLAY 0.680851 (-1563 2308);
PAINT GREEN (-1563 2308);
FORCEPROP 2 LAST CDS_LIB standard
J 0
(-1625 2300);
DISPLAY INVISIBLE (-1625 2300);
FORCEPROP 1 LAST BODY_TYPE PLUMBING
J 2
(-1625 2350);
DISPLAY 0.872340 (-1625 2350);
PAINT GREEN (-1625 2350);
DISPLAY INVISIBLE (-1625 2350);
FORCEPROP 1 LAST HDL_TAP TRUE
J 2
(-1950 2175);
DISPLAY 0.872340 (-1950 2175);
DISPLAY INVISIBLE (-1950 2175);
FORCEPROP 1 LAST PATH I46
J 2
(-1623 2300);
DISPLAY 0.872340 (-1623 2300);
PAINT GREEN (-1623 2300);
DISPLAY INVISIBLE (-1623 2300);
FORCEADD TAP..1
R 2
(-1625 2500);
FORCEPROP 3 LASTPIN (-1575 2500) SIG_NAME P5E_CPU0_PE1_TX_DP<10>
J 0
(-1565 2510);
DISPLAY 0.659574 (-1565 2510);
PAINT MONO (-1565 2510);
DISPLAY INVISIBLE (-1565 2510);
FORCEPROP 1 LASTPIN (-1575 2500) BN 10
J 2
(-1563 2508);
DISPLAY 0.680851 (-1563 2508);
PAINT GREEN (-1563 2508);
FORCEPROP 2 LAST CDS_LIB standard
J 0
(-1625 2500);
DISPLAY INVISIBLE (-1625 2500);
FORCEPROP 1 LAST BODY_TYPE PLUMBING
J 2
(-1625 2550);
DISPLAY 0.872340 (-1625 2550);
PAINT GREEN (-1625 2550);
DISPLAY INVISIBLE (-1625 2550);
FORCEPROP 1 LAST HDL_TAP TRUE
J 2
(-1950 2375);
DISPLAY 0.872340 (-1950 2375);
DISPLAY INVISIBLE (-1950 2375);
FORCEPROP 1 LAST PATH I47
J 2
(-1623 2500);
DISPLAY 0.872340 (-1623 2500);
PAINT GREEN (-1623 2500);
DISPLAY INVISIBLE (-1623 2500);
FORCEADD TAP..1
R 2
(-1625 2700);
FORCEPROP 3 LASTPIN (-1575 2700) SIG_NAME P5E_CPU0_PE1_TX_DP<11>
J 0
(-1565 2710);
DISPLAY 0.659574 (-1565 2710);
PAINT MONO (-1565 2710);
DISPLAY INVISIBLE (-1565 2710);
FORCEPROP 1 LASTPIN (-1575 2700) BN 11
J 2
(-1563 2708);
DISPLAY 0.680851 (-1563 2708);
PAINT GREEN (-1563 2708);
FORCEPROP 2 LAST CDS_LIB standard
J 0
(-1625 2700);
DISPLAY INVISIBLE (-1625 2700);
FORCEPROP 1 LAST BODY_TYPE PLUMBING
J 2
(-1625 2750);
DISPLAY 0.872340 (-1625 2750);
PAINT GREEN (-1625 2750);
DISPLAY INVISIBLE (-1625 2750);
FORCEPROP 1 LAST HDL_TAP TRUE
J 2
(-1950 2575);
DISPLAY 0.872340 (-1950 2575);
DISPLAY INVISIBLE (-1950 2575);
FORCEPROP 1 LAST PATH I48
J 2
(-1623 2700);
DISPLAY 0.872340 (-1623 2700);
PAINT GREEN (-1623 2700);
DISPLAY INVISIBLE (-1623 2700);
FORCEADD TAP..1
R 2
(-1625 2900);
FORCEPROP 3 LASTPIN (-1575 2900) SIG_NAME P5E_CPU0_PE1_TX_DP<12>
J 0
(-1565 2910);
DISPLAY 0.659574 (-1565 2910);
PAINT MONO (-1565 2910);
DISPLAY INVISIBLE (-1565 2910);
FORCEPROP 1 LASTPIN (-1575 2900) BN 12
J 2
(-1563 2908);
DISPLAY 0.680851 (-1563 2908);
PAINT GREEN (-1563 2908);
FORCEPROP 2 LAST CDS_LIB standard
J 0
(-1625 2900);
DISPLAY INVISIBLE (-1625 2900);
FORCEPROP 1 LAST BODY_TYPE PLUMBING
J 2
(-1625 2950);
DISPLAY 0.872340 (-1625 2950);
PAINT GREEN (-1625 2950);
DISPLAY INVISIBLE (-1625 2950);
FORCEPROP 1 LAST HDL_TAP TRUE
J 2
(-1950 2775);
DISPLAY 0.872340 (-1950 2775);
DISPLAY INVISIBLE (-1950 2775);
FORCEPROP 1 LAST PATH I49
J 2
(-1623 2900);
DISPLAY 0.872340 (-1623 2900);
PAINT GREEN (-1623 2900);
DISPLAY INVISIBLE (-1623 2900);
FORCEADD TAP..1
R 2
(-1625 125);
FORCEPROP 3 LASTPIN (-1575 125) SIG_NAME P5E_CPU0_PE1_TX_DP<0>
J 0
(-1565 135);
DISPLAY 0.659574 (-1565 135);
PAINT MONO (-1565 135);
DISPLAY INVISIBLE (-1565 135);
FORCEPROP 1 LASTPIN (-1575 125) BN 0
J 2
(-1563 133);
DISPLAY 0.680851 (-1563 133);
PAINT GREEN (-1563 133);
FORCEPROP 2 LAST CDS_LIB standard
J 0
(-1625 125);
DISPLAY INVISIBLE (-1625 125);
FORCEPROP 1 LAST BODY_TYPE PLUMBING
J 2
(-1625 175);
DISPLAY 0.872340 (-1625 175);
PAINT GREEN (-1625 175);
DISPLAY INVISIBLE (-1625 175);
FORCEPROP 1 LAST HDL_TAP TRUE
J 2
(-1950 0);
DISPLAY 0.872340 (-1950 0);
DISPLAY INVISIBLE (-1950 0);
FORCEPROP 1 LAST PATH I5
J 2
(-1623 125);
DISPLAY 0.872340 (-1623 125);
PAINT GREEN (-1623 125);
DISPLAY INVISIBLE (-1623 125);
FORCEADD TAP..1
R 2
(-1375 2150);
FORCEPROP 3 LASTPIN (-1325 2150) SIG_NAME P5E_CPU0_PE1_TX_DN<8>
J 0
(-1315 2160);
DISPLAY 0.659574 (-1315 2160);
PAINT MONO (-1315 2160);
DISPLAY INVISIBLE (-1315 2160);
FORCEPROP 1 LASTPIN (-1325 2150) BN 8
J 2
(-1313 2158);
DISPLAY 0.680851 (-1313 2158);
PAINT GREEN (-1313 2158);
FORCEPROP 2 LAST CDS_LIB standard
J 0
(-1375 2150);
DISPLAY INVISIBLE (-1375 2150);
FORCEPROP 1 LAST BODY_TYPE PLUMBING
J 2
(-1375 2200);
DISPLAY 0.872340 (-1375 2200);
PAINT GREEN (-1375 2200);
DISPLAY INVISIBLE (-1375 2200);
FORCEPROP 1 LAST HDL_TAP TRUE
J 2
(-1700 2025);
DISPLAY 0.872340 (-1700 2025);
DISPLAY INVISIBLE (-1700 2025);
FORCEPROP 1 LAST PATH I50
J 2
(-1373 2150);
DISPLAY 0.872340 (-1373 2150);
PAINT GREEN (-1373 2150);
DISPLAY INVISIBLE (-1373 2150);
FORCEADD TAP..1
R 2
(-1375 2350);
FORCEPROP 3 LASTPIN (-1325 2350) SIG_NAME P5E_CPU0_PE1_TX_DN<9>
J 0
(-1315 2360);
DISPLAY 0.659574 (-1315 2360);
PAINT MONO (-1315 2360);
DISPLAY INVISIBLE (-1315 2360);
FORCEPROP 1 LASTPIN (-1325 2350) BN 9
J 2
(-1313 2358);
DISPLAY 0.680851 (-1313 2358);
PAINT GREEN (-1313 2358);
FORCEPROP 2 LAST CDS_LIB standard
J 0
(-1375 2350);
DISPLAY INVISIBLE (-1375 2350);
FORCEPROP 1 LAST BODY_TYPE PLUMBING
J 2
(-1375 2400);
DISPLAY 0.872340 (-1375 2400);
PAINT GREEN (-1375 2400);
DISPLAY INVISIBLE (-1375 2400);
FORCEPROP 1 LAST HDL_TAP TRUE
J 2
(-1700 2225);
DISPLAY 0.872340 (-1700 2225);
DISPLAY INVISIBLE (-1700 2225);
FORCEPROP 1 LAST PATH I51
J 2
(-1373 2350);
DISPLAY 0.872340 (-1373 2350);
PAINT GREEN (-1373 2350);
DISPLAY INVISIBLE (-1373 2350);
FORCEADD TAP..1
R 2
(-1375 2550);
FORCEPROP 3 LASTPIN (-1325 2550) SIG_NAME P5E_CPU0_PE1_TX_DN<10>
J 0
(-1315 2560);
DISPLAY 0.659574 (-1315 2560);
PAINT MONO (-1315 2560);
DISPLAY INVISIBLE (-1315 2560);
FORCEPROP 1 LASTPIN (-1325 2550) BN 10
J 2
(-1313 2558);
DISPLAY 0.680851 (-1313 2558);
PAINT GREEN (-1313 2558);
FORCEPROP 2 LAST CDS_LIB standard
J 0
(-1375 2550);
DISPLAY INVISIBLE (-1375 2550);
FORCEPROP 1 LAST BODY_TYPE PLUMBING
J 2
(-1375 2600);
DISPLAY 0.872340 (-1375 2600);
PAINT GREEN (-1375 2600);
DISPLAY INVISIBLE (-1375 2600);
FORCEPROP 1 LAST HDL_TAP TRUE
J 2
(-1700 2425);
DISPLAY 0.872340 (-1700 2425);
DISPLAY INVISIBLE (-1700 2425);
FORCEPROP 1 LAST PATH I52
J 2
(-1373 2550);
DISPLAY 0.872340 (-1373 2550);
PAINT GREEN (-1373 2550);
DISPLAY INVISIBLE (-1373 2550);
FORCEADD TAP..1
R 2
(-1375 2750);
FORCEPROP 3 LASTPIN (-1325 2750) SIG_NAME P5E_CPU0_PE1_TX_DN<11>
J 0
(-1315 2760);
DISPLAY 0.659574 (-1315 2760);
PAINT MONO (-1315 2760);
DISPLAY INVISIBLE (-1315 2760);
FORCEPROP 1 LASTPIN (-1325 2750) BN 11
J 2
(-1313 2758);
DISPLAY 0.680851 (-1313 2758);
PAINT GREEN (-1313 2758);
FORCEPROP 2 LAST CDS_LIB standard
J 0
(-1375 2750);
DISPLAY INVISIBLE (-1375 2750);
FORCEPROP 1 LAST BODY_TYPE PLUMBING
J 2
(-1375 2800);
DISPLAY 0.872340 (-1375 2800);
PAINT GREEN (-1375 2800);
DISPLAY INVISIBLE (-1375 2800);
FORCEPROP 1 LAST HDL_TAP TRUE
J 2
(-1700 2625);
DISPLAY 0.872340 (-1700 2625);
DISPLAY INVISIBLE (-1700 2625);
FORCEPROP 1 LAST PATH I53
J 2
(-1373 2750);
DISPLAY 0.872340 (-1373 2750);
PAINT GREEN (-1373 2750);
DISPLAY INVISIBLE (-1373 2750);
FORCEADD TAP..1
R 2
(-1375 2950);
FORCEPROP 3 LASTPIN (-1325 2950) SIG_NAME P5E_CPU0_PE1_TX_DN<12>
J 0
(-1315 2960);
DISPLAY 0.659574 (-1315 2960);
PAINT MONO (-1315 2960);
DISPLAY INVISIBLE (-1315 2960);
FORCEPROP 1 LASTPIN (-1325 2950) BN 12
J 2
(-1313 2958);
DISPLAY 0.680851 (-1313 2958);
PAINT GREEN (-1313 2958);
FORCEPROP 2 LAST CDS_LIB standard
J 0
(-1375 2950);
DISPLAY INVISIBLE (-1375 2950);
FORCEPROP 1 LAST BODY_TYPE PLUMBING
J 2
(-1375 3000);
DISPLAY 0.872340 (-1375 3000);
PAINT GREEN (-1375 3000);
DISPLAY INVISIBLE (-1375 3000);
FORCEPROP 1 LAST HDL_TAP TRUE
J 2
(-1700 2825);
DISPLAY 0.872340 (-1700 2825);
DISPLAY INVISIBLE (-1700 2825);
FORCEPROP 1 LAST PATH I54
J 2
(-1373 2950);
DISPLAY 0.872340 (-1373 2950);
PAINT GREEN (-1373 2950);
DISPLAY INVISIBLE (-1373 2950);
FORCEADD TAP..1
R 2
(-1625 3500);
FORCEPROP 3 LASTPIN (-1575 3500) SIG_NAME P5E_CPU0_PE1_TX_DP<15>
J 0
(-1565 3510);
DISPLAY 0.659574 (-1565 3510);
PAINT MONO (-1565 3510);
DISPLAY INVISIBLE (-1565 3510);
FORCEPROP 1 LASTPIN (-1575 3500) BN 15
J 2
(-1563 3508);
DISPLAY 0.680851 (-1563 3508);
PAINT GREEN (-1563 3508);
FORCEPROP 2 LAST CDS_LIB standard
J 0
(-1625 3500);
DISPLAY INVISIBLE (-1625 3500);
FORCEPROP 1 LAST BODY_TYPE PLUMBING
J 2
(-1625 3550);
DISPLAY 0.872340 (-1625 3550);
PAINT GREEN (-1625 3550);
DISPLAY INVISIBLE (-1625 3550);
FORCEPROP 1 LAST HDL_TAP TRUE
J 2
(-1950 3375);
DISPLAY 0.872340 (-1950 3375);
DISPLAY INVISIBLE (-1950 3375);
FORCEPROP 1 LAST PATH I55
J 2
(-1623 3500);
DISPLAY 0.872340 (-1623 3500);
PAINT GREEN (-1623 3500);
DISPLAY INVISIBLE (-1623 3500);
FORCEADD TAP..1
R 2
(-1625 3300);
FORCEPROP 3 LASTPIN (-1575 3300) SIG_NAME P5E_CPU0_PE1_TX_DP<14>
J 0
(-1565 3310);
DISPLAY 0.659574 (-1565 3310);
PAINT MONO (-1565 3310);
DISPLAY INVISIBLE (-1565 3310);
FORCEPROP 1 LASTPIN (-1575 3300) BN 14
J 2
(-1563 3308);
DISPLAY 0.680851 (-1563 3308);
PAINT GREEN (-1563 3308);
FORCEPROP 2 LAST CDS_LIB standard
J 0
(-1625 3300);
DISPLAY INVISIBLE (-1625 3300);
FORCEPROP 1 LAST BODY_TYPE PLUMBING
J 2
(-1625 3350);
DISPLAY 0.872340 (-1625 3350);
PAINT GREEN (-1625 3350);
DISPLAY INVISIBLE (-1625 3350);
FORCEPROP 1 LAST HDL_TAP TRUE
J 2
(-1950 3175);
DISPLAY 0.872340 (-1950 3175);
DISPLAY INVISIBLE (-1950 3175);
FORCEPROP 1 LAST PATH I56
J 2
(-1623 3300);
DISPLAY 0.872340 (-1623 3300);
PAINT GREEN (-1623 3300);
DISPLAY INVISIBLE (-1623 3300);
FORCEADD TAP..1
R 2
(-1625 3100);
FORCEPROP 3 LASTPIN (-1575 3100) SIG_NAME P5E_CPU0_PE1_TX_DP<13>
J 0
(-1565 3110);
DISPLAY 0.659574 (-1565 3110);
PAINT MONO (-1565 3110);
DISPLAY INVISIBLE (-1565 3110);
FORCEPROP 1 LASTPIN (-1575 3100) BN 13
J 2
(-1563 3108);
DISPLAY 0.680851 (-1563 3108);
PAINT GREEN (-1563 3108);
FORCEPROP 2 LAST CDS_LIB standard
J 0
(-1625 3100);
DISPLAY INVISIBLE (-1625 3100);
FORCEPROP 1 LAST BODY_TYPE PLUMBING
J 2
(-1625 3150);
DISPLAY 0.872340 (-1625 3150);
PAINT GREEN (-1625 3150);
DISPLAY INVISIBLE (-1625 3150);
FORCEPROP 1 LAST HDL_TAP TRUE
J 2
(-1950 2975);
DISPLAY 0.872340 (-1950 2975);
DISPLAY INVISIBLE (-1950 2975);
FORCEPROP 1 LAST PATH I57
J 2
(-1623 3100);
DISPLAY 0.872340 (-1623 3100);
PAINT GREEN (-1623 3100);
DISPLAY INVISIBLE (-1623 3100);
FORCEADD TAP..1
R 2
(-1375 3150);
FORCEPROP 3 LASTPIN (-1325 3150) SIG_NAME P5E_CPU0_PE1_TX_DN<13>
J 0
(-1315 3160);
DISPLAY 0.659574 (-1315 3160);
PAINT MONO (-1315 3160);
DISPLAY INVISIBLE (-1315 3160);
FORCEPROP 1 LASTPIN (-1325 3150) BN 13
J 2
(-1313 3158);
DISPLAY 0.680851 (-1313 3158);
PAINT GREEN (-1313 3158);
FORCEPROP 2 LAST CDS_LIB standard
J 0
(-1375 3150);
DISPLAY INVISIBLE (-1375 3150);
FORCEPROP 1 LAST BODY_TYPE PLUMBING
J 2
(-1375 3200);
DISPLAY 0.872340 (-1375 3200);
PAINT GREEN (-1375 3200);
DISPLAY INVISIBLE (-1375 3200);
FORCEPROP 1 LAST HDL_TAP TRUE
J 2
(-1700 3025);
DISPLAY 0.872340 (-1700 3025);
DISPLAY INVISIBLE (-1700 3025);
FORCEPROP 1 LAST PATH I58
J 2
(-1373 3150);
DISPLAY 0.872340 (-1373 3150);
PAINT GREEN (-1373 3150);
DISPLAY INVISIBLE (-1373 3150);
FORCEADD TAP..1
R 2
(-1375 3350);
FORCEPROP 3 LASTPIN (-1325 3350) SIG_NAME P5E_CPU0_PE1_TX_DN<14>
J 0
(-1315 3360);
DISPLAY 0.659574 (-1315 3360);
PAINT MONO (-1315 3360);
DISPLAY INVISIBLE (-1315 3360);
FORCEPROP 1 LASTPIN (-1325 3350) BN 14
J 2
(-1313 3358);
DISPLAY 0.680851 (-1313 3358);
PAINT GREEN (-1313 3358);
FORCEPROP 2 LAST CDS_LIB standard
J 0
(-1375 3350);
DISPLAY INVISIBLE (-1375 3350);
FORCEPROP 1 LAST BODY_TYPE PLUMBING
J 2
(-1375 3400);
DISPLAY 0.872340 (-1375 3400);
PAINT GREEN (-1375 3400);
DISPLAY INVISIBLE (-1375 3400);
FORCEPROP 1 LAST HDL_TAP TRUE
J 2
(-1700 3225);
DISPLAY 0.872340 (-1700 3225);
DISPLAY INVISIBLE (-1700 3225);
FORCEPROP 1 LAST PATH I59
J 2
(-1373 3350);
DISPLAY 0.872340 (-1373 3350);
PAINT GREEN (-1373 3350);
DISPLAY INVISIBLE (-1373 3350);
FORCEADD TAP..1
R 2
(-1625 325);
FORCEPROP 3 LASTPIN (-1575 325) SIG_NAME P5E_CPU0_PE1_TX_DP<1>
J 0
(-1565 335);
DISPLAY 0.659574 (-1565 335);
PAINT MONO (-1565 335);
DISPLAY INVISIBLE (-1565 335);
FORCEPROP 1 LASTPIN (-1575 325) BN 1
J 2
(-1563 333);
DISPLAY 0.680851 (-1563 333);
PAINT GREEN (-1563 333);
FORCEPROP 2 LAST CDS_LIB standard
J 0
(-1625 325);
DISPLAY INVISIBLE (-1625 325);
FORCEPROP 1 LAST BODY_TYPE PLUMBING
J 2
(-1625 375);
DISPLAY 0.872340 (-1625 375);
PAINT GREEN (-1625 375);
DISPLAY INVISIBLE (-1625 375);
FORCEPROP 1 LAST HDL_TAP TRUE
J 2
(-1950 200);
DISPLAY 0.872340 (-1950 200);
DISPLAY INVISIBLE (-1950 200);
FORCEPROP 1 LAST PATH I6
J 2
(-1623 325);
DISPLAY 0.872340 (-1623 325);
PAINT GREEN (-1623 325);
DISPLAY INVISIBLE (-1623 325);
FORCEADD TAP..1
R 2
(-1375 3550);
FORCEPROP 3 LASTPIN (-1325 3550) SIG_NAME P5E_CPU0_PE1_TX_DN<15>
J 0
(-1315 3560);
DISPLAY 0.659574 (-1315 3560);
PAINT MONO (-1315 3560);
DISPLAY INVISIBLE (-1315 3560);
FORCEPROP 1 LASTPIN (-1325 3550) BN 15
J 2
(-1313 3558);
DISPLAY 0.680851 (-1313 3558);
PAINT GREEN (-1313 3558);
FORCEPROP 2 LAST CDS_LIB standard
J 0
(-1375 3550);
DISPLAY INVISIBLE (-1375 3550);
FORCEPROP 1 LAST BODY_TYPE PLUMBING
J 2
(-1375 3600);
DISPLAY 0.872340 (-1375 3600);
PAINT GREEN (-1375 3600);
DISPLAY INVISIBLE (-1375 3600);
FORCEPROP 1 LAST HDL_TAP TRUE
J 2
(-1700 3425);
DISPLAY 0.872340 (-1700 3425);
DISPLAY INVISIBLE (-1700 3425);
FORCEPROP 1 LAST PATH I60
J 2
(-1373 3550);
DISPLAY 0.872340 (-1373 3550);
PAINT GREEN (-1373 3550);
DISPLAY INVISIBLE (-1373 3550);
FORCEADD Q_CAP_DIFFBUS..2
R 2
(-650 2150);
FORCEPROP 1 LAST PART_NUMBER SP_CH4221MEE01
J 2
(-766 2238);
DISPLAY 0.574468 (-766 2238);
PAINT GREEN (-766 2238);
DISPLAY INVISIBLE (-766 2238);
FORCEPROP 2 LAST VALUE DIFF BUS_0.22UF
J 2
(-800 2150);
DISPLAY 0.553191 (-800 2150);
FORCEPROP 1 LAST $LOCATION C852
J 2
(-416 2167);
DISPLAY 0.723404 (-416 2167);
PAINT GREEN (-416 2167);
FORCEPROP 2 LASTPIN (-575 2150) $PN 1
J 0
(-565 2160);
DISPLAY 0.808511 (-565 2160);
FORCEPROP 2 LASTPIN (-725 2150) $PN 2
J 2
(-735 2160);
DISPLAY 0.808511 (-735 2160);
FORCEPROP 2 LAST TOLERANCE 20%
J 2
(-725 2200);
DISPLAY 0.553191 (-725 2200);
DISPLAY INVISIBLE (-725 2200);
FORCEPROP 2 LAST PACK_TYPE C0201
J 2
(-825 2200);
DISPLAY 0.553191 (-825 2200);
DISPLAY INVISIBLE (-825 2200);
FORCEPROP 1 LAST MATERIAL X6S
J 2
(-641 2229);
DISPLAY 0.574468 (-641 2229);
PAINT GREEN (-641 2229);
DISPLAY INVISIBLE (-641 2229);
FORCEPROP 2 LAST VOLTAGE 6.3V
J 2
(-1000 2200);
DISPLAY 0.553191 (-1000 2200);
DISPLAY INVISIBLE (-1000 2200);
FORCEPROP 1 LAST PIN_NAMES_ROTATE TRUE
J 2
(-650 2150);
DISPLAY 0.489362 (-650 2150);
PAINT GREEN (-650 2150);
DISPLAY INVISIBLE (-650 2150);
FORCEPROP 2 LAST CDS_LIB pure_quanta
J 2
(-650 2150);
DISPLAY INVISIBLE (-650 2150);
FORCEPROP 1 LAST CDS_LMAN_SYM_OUTLINE -25,50,25,-50
J 2
(-650 2150);
DISPLAY 0.468085 (-650 2150);
PAINT GREEN (-650 2150);
DISPLAY INVISIBLE (-650 2150);
FORCEPROP 1 LAST PATH I61
J 2
(-650 2150);
DISPLAY 0.723404 (-650 2150);
DISPLAY INVISIBLE (-650 2150);
FORCEPROP 1 LAST $LOCATION C852
J 0
(-400 2225);
DISPLAY 1.021277 (-400 2225);
DISPLAY INVISIBLE (-400 2225);
FORCEPROP 2 LAST CDS_LOCATION C852
J 0
(-400 2225);
DISPLAY 1.021277 (-400 2225);
DISPLAY INVISIBLE (-400 2225);
FORCEPROP 2 LAST $SEC 1
J 2
(-475 2225);
DISPLAY 0.680851 (-475 2225);
PAINT MONO (-475 2225);
DISPLAY INVISIBLE (-475 2225);
FORCEPROP 2 LAST CDS_SEC 1
J 2
(-475 2225);
DISPLAY 0.680851 (-475 2225);
DISPLAY INVISIBLE (-475 2225);
FORCEADD Q_CAP_DIFFBUS..2
R 2
(-650 2100);
FORCEPROP 1 LAST PART_NUMBER SP_CH4221MEE01
J 2
(-766 2188);
DISPLAY 0.574468 (-766 2188);
PAINT GREEN (-766 2188);
DISPLAY INVISIBLE (-766 2188);
FORCEPROP 2 LAST VALUE DIFF BUS_0.22UF
J 2
(-800 2100);
DISPLAY 0.553191 (-800 2100);
FORCEPROP 1 LAST $LOCATION C853
J 2
(-416 2117);
DISPLAY 0.723404 (-416 2117);
PAINT GREEN (-416 2117);
FORCEPROP 2 LASTPIN (-575 2100) $PN 1
J 0
(-565 2110);
DISPLAY 0.808511 (-565 2110);
FORCEPROP 2 LASTPIN (-725 2100) $PN 2
J 2
(-735 2110);
DISPLAY 0.808511 (-735 2110);
FORCEPROP 2 LAST TOLERANCE 20%
J 2
(-725 2150);
DISPLAY 0.553191 (-725 2150);
DISPLAY INVISIBLE (-725 2150);
FORCEPROP 2 LAST PACK_TYPE C0201
J 2
(-825 2150);
DISPLAY 0.553191 (-825 2150);
DISPLAY INVISIBLE (-825 2150);
FORCEPROP 1 LAST MATERIAL X6S
J 2
(-641 2179);
DISPLAY 0.574468 (-641 2179);
PAINT GREEN (-641 2179);
DISPLAY INVISIBLE (-641 2179);
FORCEPROP 2 LAST VOLTAGE 6.3V
J 2
(-1000 2150);
DISPLAY 0.553191 (-1000 2150);
DISPLAY INVISIBLE (-1000 2150);
FORCEPROP 1 LAST PIN_NAMES_ROTATE TRUE
J 2
(-650 2100);
DISPLAY 0.489362 (-650 2100);
PAINT GREEN (-650 2100);
DISPLAY INVISIBLE (-650 2100);
FORCEPROP 2 LAST CDS_LIB pure_quanta
J 2
(-650 2100);
DISPLAY INVISIBLE (-650 2100);
FORCEPROP 1 LAST CDS_LMAN_SYM_OUTLINE -25,50,25,-50
J 2
(-650 2100);
DISPLAY 0.468085 (-650 2100);
PAINT GREEN (-650 2100);
DISPLAY INVISIBLE (-650 2100);
FORCEPROP 1 LAST PATH I62
J 2
(-650 2100);
DISPLAY 0.723404 (-650 2100);
DISPLAY INVISIBLE (-650 2100);
FORCEPROP 1 LAST $LOCATION C853
J 0
(-400 2175);
DISPLAY 1.021277 (-400 2175);
DISPLAY INVISIBLE (-400 2175);
FORCEPROP 2 LAST CDS_LOCATION C853
J 0
(-400 2175);
DISPLAY 1.021277 (-400 2175);
DISPLAY INVISIBLE (-400 2175);
FORCEPROP 2 LAST $SEC 1
J 2
(-475 2175);
DISPLAY 0.680851 (-475 2175);
PAINT MONO (-475 2175);
DISPLAY INVISIBLE (-475 2175);
FORCEPROP 2 LAST CDS_SEC 1
J 2
(-475 2175);
DISPLAY 0.680851 (-475 2175);
DISPLAY INVISIBLE (-475 2175);
FORCEADD Q_CAP_DIFFBUS..2
R 2
(-650 2300);
FORCEPROP 1 LAST PART_NUMBER SP_CH4221MEE01
J 2
(-766 2388);
DISPLAY 0.574468 (-766 2388);
PAINT GREEN (-766 2388);
DISPLAY INVISIBLE (-766 2388);
FORCEPROP 2 LAST VALUE DIFF BUS_0.22UF
J 2
(-800 2300);
DISPLAY 0.553191 (-800 2300);
FORCEPROP 1 LAST $LOCATION C851
J 2
(-416 2317);
DISPLAY 0.723404 (-416 2317);
PAINT GREEN (-416 2317);
FORCEPROP 2 LASTPIN (-575 2300) $PN 1
J 0
(-565 2310);
DISPLAY 0.808511 (-565 2310);
FORCEPROP 2 LASTPIN (-725 2300) $PN 2
J 2
(-735 2310);
DISPLAY 0.808511 (-735 2310);
FORCEPROP 2 LAST TOLERANCE 20%
J 2
(-725 2350);
DISPLAY 0.553191 (-725 2350);
DISPLAY INVISIBLE (-725 2350);
FORCEPROP 2 LAST PACK_TYPE C0201
J 2
(-825 2350);
DISPLAY 0.553191 (-825 2350);
DISPLAY INVISIBLE (-825 2350);
FORCEPROP 1 LAST MATERIAL X6S
J 2
(-641 2379);
DISPLAY 0.574468 (-641 2379);
PAINT GREEN (-641 2379);
DISPLAY INVISIBLE (-641 2379);
FORCEPROP 2 LAST VOLTAGE 6.3V
J 2
(-1000 2350);
DISPLAY 0.553191 (-1000 2350);
DISPLAY INVISIBLE (-1000 2350);
FORCEPROP 1 LAST PIN_NAMES_ROTATE TRUE
J 2
(-650 2300);
DISPLAY 0.489362 (-650 2300);
PAINT GREEN (-650 2300);
DISPLAY INVISIBLE (-650 2300);
FORCEPROP 2 LAST CDS_LIB pure_quanta
J 2
(-650 2300);
DISPLAY INVISIBLE (-650 2300);
FORCEPROP 1 LAST CDS_LMAN_SYM_OUTLINE -25,50,25,-50
J 2
(-650 2300);
DISPLAY 0.468085 (-650 2300);
PAINT GREEN (-650 2300);
DISPLAY INVISIBLE (-650 2300);
FORCEPROP 1 LAST PATH I63
J 2
(-650 2300);
DISPLAY 0.723404 (-650 2300);
DISPLAY INVISIBLE (-650 2300);
FORCEPROP 1 LAST $LOCATION C851
J 0
(-400 2375);
DISPLAY 1.021277 (-400 2375);
DISPLAY INVISIBLE (-400 2375);
FORCEPROP 2 LAST CDS_LOCATION C851
J 0
(-400 2375);
DISPLAY 1.021277 (-400 2375);
DISPLAY INVISIBLE (-400 2375);
FORCEPROP 2 LAST $SEC 1
J 2
(-475 2375);
DISPLAY 0.680851 (-475 2375);
PAINT MONO (-475 2375);
DISPLAY INVISIBLE (-475 2375);
FORCEPROP 2 LAST CDS_SEC 1
J 2
(-475 2375);
DISPLAY 0.680851 (-475 2375);
DISPLAY INVISIBLE (-475 2375);
FORCEADD Q_CAP_DIFFBUS..2
R 2
(-650 2350);
FORCEPROP 1 LAST PART_NUMBER SP_CH4221MEE01
J 2
(-766 2438);
DISPLAY 0.574468 (-766 2438);
PAINT GREEN (-766 2438);
DISPLAY INVISIBLE (-766 2438);
FORCEPROP 2 LAST VALUE DIFF BUS_0.22UF
J 2
(-800 2350);
DISPLAY 0.553191 (-800 2350);
FORCEPROP 1 LAST $LOCATION C850
J 2
(-416 2367);
DISPLAY 0.723404 (-416 2367);
PAINT GREEN (-416 2367);
FORCEPROP 2 LASTPIN (-575 2350) $PN 1
J 0
(-565 2360);
DISPLAY 0.808511 (-565 2360);
FORCEPROP 2 LASTPIN (-725 2350) $PN 2
J 2
(-735 2360);
DISPLAY 0.808511 (-735 2360);
FORCEPROP 2 LAST TOLERANCE 20%
J 2
(-725 2400);
DISPLAY 0.553191 (-725 2400);
DISPLAY INVISIBLE (-725 2400);
FORCEPROP 2 LAST PACK_TYPE C0201
J 2
(-825 2400);
DISPLAY 0.553191 (-825 2400);
DISPLAY INVISIBLE (-825 2400);
FORCEPROP 1 LAST MATERIAL X6S
J 2
(-641 2429);
DISPLAY 0.574468 (-641 2429);
PAINT GREEN (-641 2429);
DISPLAY INVISIBLE (-641 2429);
FORCEPROP 2 LAST VOLTAGE 6.3V
J 2
(-1000 2400);
DISPLAY 0.553191 (-1000 2400);
DISPLAY INVISIBLE (-1000 2400);
FORCEPROP 1 LAST PIN_NAMES_ROTATE TRUE
J 2
(-650 2350);
DISPLAY 0.489362 (-650 2350);
PAINT GREEN (-650 2350);
DISPLAY INVISIBLE (-650 2350);
FORCEPROP 1 LAST CDS_LMAN_SYM_OUTLINE -25,50,25,-50
J 2
(-650 2350);
DISPLAY 0.468085 (-650 2350);
PAINT GREEN (-650 2350);
DISPLAY INVISIBLE (-650 2350);
FORCEPROP 2 LAST CDS_LIB pure_quanta
J 2
(-650 2350);
DISPLAY INVISIBLE (-650 2350);
FORCEPROP 1 LAST PATH I64
J 2
(-650 2350);
DISPLAY 0.723404 (-650 2350);
DISPLAY INVISIBLE (-650 2350);
FORCEPROP 1 LAST $LOCATION C850
J 0
(-400 2425);
DISPLAY 1.021277 (-400 2425);
DISPLAY INVISIBLE (-400 2425);
FORCEPROP 2 LAST CDS_LOCATION C850
J 0
(-400 2425);
DISPLAY 1.021277 (-400 2425);
DISPLAY INVISIBLE (-400 2425);
FORCEPROP 2 LAST $SEC 1
J 2
(-475 2425);
DISPLAY 0.680851 (-475 2425);
PAINT MONO (-475 2425);
DISPLAY INVISIBLE (-475 2425);
FORCEPROP 2 LAST CDS_SEC 1
J 2
(-475 2425);
DISPLAY 0.680851 (-475 2425);
DISPLAY INVISIBLE (-475 2425);
FORCEADD Q_CAP_DIFFBUS..2
R 2
(-650 2500);
FORCEPROP 1 LAST PART_NUMBER SP_CH4221MEE01
J 2
(-766 2588);
DISPLAY 0.574468 (-766 2588);
PAINT GREEN (-766 2588);
DISPLAY INVISIBLE (-766 2588);
FORCEPROP 2 LAST VALUE DIFF BUS_0.22UF
J 2
(-800 2500);
DISPLAY 0.553191 (-800 2500);
FORCEPROP 1 LAST $LOCATION C849
J 2
(-416 2517);
DISPLAY 0.723404 (-416 2517);
PAINT GREEN (-416 2517);
FORCEPROP 2 LASTPIN (-575 2500) $PN 1
J 0
(-565 2510);
DISPLAY 0.808511 (-565 2510);
FORCEPROP 2 LASTPIN (-725 2500) $PN 2
J 2
(-735 2510);
DISPLAY 0.808511 (-735 2510);
FORCEPROP 2 LAST TOLERANCE 20%
J 2
(-725 2550);
DISPLAY 0.553191 (-725 2550);
DISPLAY INVISIBLE (-725 2550);
FORCEPROP 2 LAST PACK_TYPE C0201
J 2
(-825 2550);
DISPLAY 0.553191 (-825 2550);
DISPLAY INVISIBLE (-825 2550);
FORCEPROP 1 LAST MATERIAL X6S
J 2
(-641 2579);
DISPLAY 0.574468 (-641 2579);
PAINT GREEN (-641 2579);
DISPLAY INVISIBLE (-641 2579);
FORCEPROP 2 LAST VOLTAGE 6.3V
J 2
(-1000 2550);
DISPLAY 0.553191 (-1000 2550);
DISPLAY INVISIBLE (-1000 2550);
FORCEPROP 1 LAST PIN_NAMES_ROTATE TRUE
J 2
(-650 2500);
DISPLAY 0.489362 (-650 2500);
PAINT GREEN (-650 2500);
DISPLAY INVISIBLE (-650 2500);
FORCEPROP 2 LAST CDS_LIB pure_quanta
J 2
(-650 2500);
DISPLAY INVISIBLE (-650 2500);
FORCEPROP 1 LAST CDS_LMAN_SYM_OUTLINE -25,50,25,-50
J 2
(-650 2500);
DISPLAY 0.468085 (-650 2500);
PAINT GREEN (-650 2500);
DISPLAY INVISIBLE (-650 2500);
FORCEPROP 1 LAST PATH I65
J 2
(-650 2500);
DISPLAY 0.723404 (-650 2500);
DISPLAY INVISIBLE (-650 2500);
FORCEPROP 1 LAST $LOCATION C849
J 0
(-400 2575);
DISPLAY 1.021277 (-400 2575);
DISPLAY INVISIBLE (-400 2575);
FORCEPROP 2 LAST CDS_LOCATION C849
J 0
(-400 2575);
DISPLAY 1.021277 (-400 2575);
DISPLAY INVISIBLE (-400 2575);
FORCEPROP 2 LAST $SEC 1
J 2
(-475 2575);
DISPLAY 0.680851 (-475 2575);
PAINT MONO (-475 2575);
DISPLAY INVISIBLE (-475 2575);
FORCEPROP 2 LAST CDS_SEC 1
J 2
(-475 2575);
DISPLAY 0.680851 (-475 2575);
DISPLAY INVISIBLE (-475 2575);
FORCEADD Q_CAP_DIFFBUS..2
R 2
(-650 2550);
FORCEPROP 1 LAST PART_NUMBER SP_CH4221MEE01
J 2
(-766 2638);
DISPLAY 0.574468 (-766 2638);
PAINT GREEN (-766 2638);
DISPLAY INVISIBLE (-766 2638);
FORCEPROP 2 LAST VALUE DIFF BUS_0.22UF
J 2
(-800 2550);
DISPLAY 0.553191 (-800 2550);
FORCEPROP 1 LAST $LOCATION C848
J 2
(-416 2567);
DISPLAY 0.723404 (-416 2567);
PAINT GREEN (-416 2567);
FORCEPROP 2 LASTPIN (-575 2550) $PN 1
J 0
(-565 2560);
DISPLAY 0.808511 (-565 2560);
FORCEPROP 2 LASTPIN (-725 2550) $PN 2
J 2
(-735 2560);
DISPLAY 0.808511 (-735 2560);
FORCEPROP 2 LAST TOLERANCE 20%
J 2
(-725 2600);
DISPLAY 0.553191 (-725 2600);
DISPLAY INVISIBLE (-725 2600);
FORCEPROP 2 LAST PACK_TYPE C0201
J 2
(-825 2600);
DISPLAY 0.553191 (-825 2600);
DISPLAY INVISIBLE (-825 2600);
FORCEPROP 1 LAST MATERIAL X6S
J 2
(-641 2629);
DISPLAY 0.574468 (-641 2629);
PAINT GREEN (-641 2629);
DISPLAY INVISIBLE (-641 2629);
FORCEPROP 2 LAST VOLTAGE 6.3V
J 2
(-1000 2600);
DISPLAY 0.553191 (-1000 2600);
DISPLAY INVISIBLE (-1000 2600);
FORCEPROP 1 LAST PIN_NAMES_ROTATE TRUE
J 2
(-650 2550);
DISPLAY 0.489362 (-650 2550);
PAINT GREEN (-650 2550);
DISPLAY INVISIBLE (-650 2550);
FORCEPROP 2 LAST CDS_LIB pure_quanta
J 2
(-650 2550);
DISPLAY INVISIBLE (-650 2550);
FORCEPROP 1 LAST CDS_LMAN_SYM_OUTLINE -25,50,25,-50
J 2
(-650 2550);
DISPLAY 0.468085 (-650 2550);
PAINT GREEN (-650 2550);
DISPLAY INVISIBLE (-650 2550);
FORCEPROP 1 LAST PATH I66
J 2
(-650 2550);
DISPLAY 0.723404 (-650 2550);
DISPLAY INVISIBLE (-650 2550);
FORCEPROP 1 LAST $LOCATION C848
J 0
(-400 2625);
DISPLAY 1.021277 (-400 2625);
DISPLAY INVISIBLE (-400 2625);
FORCEPROP 2 LAST CDS_LOCATION C848
J 0
(-400 2625);
DISPLAY 1.021277 (-400 2625);
DISPLAY INVISIBLE (-400 2625);
FORCEPROP 2 LAST $SEC 1
J 2
(-475 2625);
DISPLAY 0.680851 (-475 2625);
PAINT MONO (-475 2625);
DISPLAY INVISIBLE (-475 2625);
FORCEPROP 2 LAST CDS_SEC 1
J 2
(-475 2625);
DISPLAY 0.680851 (-475 2625);
DISPLAY INVISIBLE (-475 2625);
FORCEADD Q_CAP_DIFFBUS..2
R 2
(-650 2700);
FORCEPROP 1 LAST PART_NUMBER SP_CH4221MEE01
J 2
(-766 2788);
DISPLAY 0.574468 (-766 2788);
PAINT GREEN (-766 2788);
DISPLAY INVISIBLE (-766 2788);
FORCEPROP 2 LAST VALUE DIFF BUS_0.22UF
J 2
(-800 2700);
DISPLAY 0.553191 (-800 2700);
FORCEPROP 1 LAST $LOCATION C847
J 2
(-416 2717);
DISPLAY 0.723404 (-416 2717);
PAINT GREEN (-416 2717);
FORCEPROP 2 LASTPIN (-575 2700) $PN 1
J 0
(-565 2710);
DISPLAY 0.808511 (-565 2710);
FORCEPROP 2 LASTPIN (-725 2700) $PN 2
J 2
(-735 2710);
DISPLAY 0.808511 (-735 2710);
FORCEPROP 2 LAST TOLERANCE 20%
J 2
(-725 2750);
DISPLAY 0.553191 (-725 2750);
DISPLAY INVISIBLE (-725 2750);
FORCEPROP 2 LAST PACK_TYPE C0201
J 2
(-825 2750);
DISPLAY 0.553191 (-825 2750);
DISPLAY INVISIBLE (-825 2750);
FORCEPROP 1 LAST MATERIAL X6S
J 2
(-641 2779);
DISPLAY 0.574468 (-641 2779);
PAINT GREEN (-641 2779);
DISPLAY INVISIBLE (-641 2779);
FORCEPROP 2 LAST VOLTAGE 6.3V
J 2
(-1000 2750);
DISPLAY 0.553191 (-1000 2750);
DISPLAY INVISIBLE (-1000 2750);
FORCEPROP 1 LAST PIN_NAMES_ROTATE TRUE
J 2
(-650 2700);
DISPLAY 0.489362 (-650 2700);
PAINT GREEN (-650 2700);
DISPLAY INVISIBLE (-650 2700);
FORCEPROP 1 LAST CDS_LMAN_SYM_OUTLINE -25,50,25,-50
J 2
(-650 2700);
DISPLAY 0.468085 (-650 2700);
PAINT GREEN (-650 2700);
DISPLAY INVISIBLE (-650 2700);
FORCEPROP 2 LAST CDS_LIB pure_quanta
J 2
(-650 2700);
DISPLAY INVISIBLE (-650 2700);
FORCEPROP 1 LAST PATH I67
J 2
(-650 2700);
DISPLAY 0.723404 (-650 2700);
DISPLAY INVISIBLE (-650 2700);
FORCEPROP 1 LAST $LOCATION C847
J 0
(-400 2775);
DISPLAY 1.021277 (-400 2775);
DISPLAY INVISIBLE (-400 2775);
FORCEPROP 2 LAST CDS_LOCATION C847
J 0
(-400 2775);
DISPLAY 1.021277 (-400 2775);
DISPLAY INVISIBLE (-400 2775);
FORCEPROP 2 LAST $SEC 1
J 2
(-475 2775);
DISPLAY 0.680851 (-475 2775);
PAINT MONO (-475 2775);
DISPLAY INVISIBLE (-475 2775);
FORCEPROP 2 LAST CDS_SEC 1
J 2
(-475 2775);
DISPLAY 0.680851 (-475 2775);
DISPLAY INVISIBLE (-475 2775);
FORCEADD Q_CAP_DIFFBUS..2
R 2
(-650 2750);
FORCEPROP 1 LAST PART_NUMBER SP_CH4221MEE01
J 2
(-766 2838);
DISPLAY 0.574468 (-766 2838);
PAINT GREEN (-766 2838);
DISPLAY INVISIBLE (-766 2838);
FORCEPROP 2 LAST VALUE DIFF BUS_0.22UF
J 2
(-800 2750);
DISPLAY 0.553191 (-800 2750);
FORCEPROP 1 LAST $LOCATION C846
J 2
(-416 2767);
DISPLAY 0.723404 (-416 2767);
PAINT GREEN (-416 2767);
FORCEPROP 2 LASTPIN (-575 2750) $PN 1
J 0
(-565 2760);
DISPLAY 0.808511 (-565 2760);
FORCEPROP 2 LASTPIN (-725 2750) $PN 2
J 2
(-735 2760);
DISPLAY 0.808511 (-735 2760);
FORCEPROP 2 LAST TOLERANCE 20%
J 2
(-725 2800);
DISPLAY 0.553191 (-725 2800);
DISPLAY INVISIBLE (-725 2800);
FORCEPROP 2 LAST PACK_TYPE C0201
J 2
(-825 2800);
DISPLAY 0.553191 (-825 2800);
DISPLAY INVISIBLE (-825 2800);
FORCEPROP 1 LAST MATERIAL X6S
J 2
(-641 2829);
DISPLAY 0.574468 (-641 2829);
PAINT GREEN (-641 2829);
DISPLAY INVISIBLE (-641 2829);
FORCEPROP 2 LAST VOLTAGE 6.3V
J 2
(-1000 2800);
DISPLAY 0.553191 (-1000 2800);
DISPLAY INVISIBLE (-1000 2800);
FORCEPROP 1 LAST PIN_NAMES_ROTATE TRUE
J 2
(-650 2750);
DISPLAY 0.489362 (-650 2750);
PAINT GREEN (-650 2750);
DISPLAY INVISIBLE (-650 2750);
FORCEPROP 1 LAST CDS_LMAN_SYM_OUTLINE -25,50,25,-50
J 2
(-650 2750);
DISPLAY 0.468085 (-650 2750);
PAINT GREEN (-650 2750);
DISPLAY INVISIBLE (-650 2750);
FORCEPROP 2 LAST CDS_LIB pure_quanta
J 2
(-650 2750);
DISPLAY INVISIBLE (-650 2750);
FORCEPROP 1 LAST PATH I68
J 2
(-650 2750);
DISPLAY 0.723404 (-650 2750);
DISPLAY INVISIBLE (-650 2750);
FORCEPROP 1 LAST $LOCATION C846
J 0
(-400 2825);
DISPLAY 1.021277 (-400 2825);
DISPLAY INVISIBLE (-400 2825);
FORCEPROP 2 LAST CDS_LOCATION C846
J 0
(-400 2825);
DISPLAY 1.021277 (-400 2825);
DISPLAY INVISIBLE (-400 2825);
FORCEPROP 2 LAST $SEC 1
J 2
(-475 2825);
DISPLAY 0.680851 (-475 2825);
PAINT MONO (-475 2825);
DISPLAY INVISIBLE (-475 2825);
FORCEPROP 2 LAST CDS_SEC 1
J 2
(-475 2825);
DISPLAY 0.680851 (-475 2825);
DISPLAY INVISIBLE (-475 2825);
FORCEADD Q_CAP_DIFFBUS..2
R 2
(-650 2900);
FORCEPROP 1 LAST PART_NUMBER SP_CH4221MEE01
J 2
(-766 2988);
DISPLAY 0.574468 (-766 2988);
PAINT GREEN (-766 2988);
DISPLAY INVISIBLE (-766 2988);
FORCEPROP 2 LAST VALUE DIFF BUS_0.22UF
J 2
(-800 2900);
DISPLAY 0.553191 (-800 2900);
FORCEPROP 1 LAST $LOCATION C845
J 2
(-416 2917);
DISPLAY 0.723404 (-416 2917);
PAINT GREEN (-416 2917);
FORCEPROP 2 LASTPIN (-575 2900) $PN 1
J 0
(-565 2910);
DISPLAY 0.808511 (-565 2910);
FORCEPROP 2 LASTPIN (-725 2900) $PN 2
J 2
(-735 2910);
DISPLAY 0.808511 (-735 2910);
FORCEPROP 2 LAST TOLERANCE 20%
J 2
(-725 2950);
DISPLAY 0.553191 (-725 2950);
DISPLAY INVISIBLE (-725 2950);
FORCEPROP 2 LAST PACK_TYPE C0201
J 2
(-825 2950);
DISPLAY 0.553191 (-825 2950);
DISPLAY INVISIBLE (-825 2950);
FORCEPROP 1 LAST MATERIAL X6S
J 2
(-641 2979);
DISPLAY 0.574468 (-641 2979);
PAINT GREEN (-641 2979);
DISPLAY INVISIBLE (-641 2979);
FORCEPROP 2 LAST VOLTAGE 6.3V
J 2
(-1000 2950);
DISPLAY 0.553191 (-1000 2950);
DISPLAY INVISIBLE (-1000 2950);
FORCEPROP 1 LAST PIN_NAMES_ROTATE TRUE
J 2
(-650 2900);
DISPLAY 0.489362 (-650 2900);
PAINT GREEN (-650 2900);
DISPLAY INVISIBLE (-650 2900);
FORCEPROP 2 LAST CDS_LIB pure_quanta
J 2
(-650 2900);
DISPLAY INVISIBLE (-650 2900);
FORCEPROP 1 LAST CDS_LMAN_SYM_OUTLINE -25,50,25,-50
J 2
(-650 2900);
DISPLAY 0.468085 (-650 2900);
PAINT GREEN (-650 2900);
DISPLAY INVISIBLE (-650 2900);
FORCEPROP 1 LAST PATH I69
J 2
(-650 2900);
DISPLAY 0.723404 (-650 2900);
DISPLAY INVISIBLE (-650 2900);
FORCEPROP 1 LAST $LOCATION C845
J 0
(-400 2975);
DISPLAY 1.021277 (-400 2975);
DISPLAY INVISIBLE (-400 2975);
FORCEPROP 2 LAST CDS_LOCATION C845
J 0
(-400 2975);
DISPLAY 1.021277 (-400 2975);
DISPLAY INVISIBLE (-400 2975);
FORCEPROP 2 LAST $SEC 1
J 2
(-475 2975);
DISPLAY 0.680851 (-475 2975);
PAINT MONO (-475 2975);
DISPLAY INVISIBLE (-475 2975);
FORCEPROP 2 LAST CDS_SEC 1
J 2
(-475 2975);
DISPLAY 0.680851 (-475 2975);
DISPLAY INVISIBLE (-475 2975);
FORCEADD TAP..1
R 2
(-1625 525);
FORCEPROP 3 LASTPIN (-1575 525) SIG_NAME P5E_CPU0_PE1_TX_DP<2>
J 0
(-1565 535);
DISPLAY 0.659574 (-1565 535);
PAINT MONO (-1565 535);
DISPLAY INVISIBLE (-1565 535);
FORCEPROP 1 LASTPIN (-1575 525) BN 2
J 2
(-1563 533);
DISPLAY 0.680851 (-1563 533);
PAINT GREEN (-1563 533);
FORCEPROP 2 LAST CDS_LIB standard
J 0
(-1625 525);
DISPLAY INVISIBLE (-1625 525);
FORCEPROP 1 LAST BODY_TYPE PLUMBING
J 2
(-1625 575);
DISPLAY 0.872340 (-1625 575);
PAINT GREEN (-1625 575);
DISPLAY INVISIBLE (-1625 575);
FORCEPROP 1 LAST HDL_TAP TRUE
J 2
(-1950 400);
DISPLAY 0.872340 (-1950 400);
DISPLAY INVISIBLE (-1950 400);
FORCEPROP 1 LAST PATH I7
J 2
(-1623 525);
DISPLAY 0.872340 (-1623 525);
PAINT GREEN (-1623 525);
DISPLAY INVISIBLE (-1623 525);
FORCEADD Q_CAP_DIFFBUS..2
R 2
(-650 2950);
FORCEPROP 1 LAST PART_NUMBER SP_CH4221MEE01
J 2
(-766 3038);
DISPLAY 0.574468 (-766 3038);
PAINT GREEN (-766 3038);
DISPLAY INVISIBLE (-766 3038);
FORCEPROP 2 LAST VALUE DIFF BUS_0.22UF
J 2
(-800 2950);
DISPLAY 0.553191 (-800 2950);
FORCEPROP 1 LAST $LOCATION C844
J 2
(-416 2967);
DISPLAY 0.723404 (-416 2967);
PAINT GREEN (-416 2967);
FORCEPROP 2 LASTPIN (-575 2950) $PN 1
J 0
(-565 2960);
DISPLAY 0.808511 (-565 2960);
FORCEPROP 2 LASTPIN (-725 2950) $PN 2
J 2
(-735 2960);
DISPLAY 0.808511 (-735 2960);
FORCEPROP 2 LAST TOLERANCE 20%
J 2
(-725 3000);
DISPLAY 0.553191 (-725 3000);
DISPLAY INVISIBLE (-725 3000);
FORCEPROP 2 LAST PACK_TYPE C0201
J 2
(-825 3000);
DISPLAY 0.553191 (-825 3000);
DISPLAY INVISIBLE (-825 3000);
FORCEPROP 1 LAST MATERIAL X6S
J 2
(-641 3029);
DISPLAY 0.574468 (-641 3029);
PAINT GREEN (-641 3029);
DISPLAY INVISIBLE (-641 3029);
FORCEPROP 2 LAST VOLTAGE 6.3V
J 2
(-1000 3000);
DISPLAY 0.553191 (-1000 3000);
DISPLAY INVISIBLE (-1000 3000);
FORCEPROP 1 LAST PIN_NAMES_ROTATE TRUE
J 2
(-650 2950);
DISPLAY 0.489362 (-650 2950);
PAINT GREEN (-650 2950);
DISPLAY INVISIBLE (-650 2950);
FORCEPROP 2 LAST CDS_LIB pure_quanta
J 2
(-650 2950);
DISPLAY INVISIBLE (-650 2950);
FORCEPROP 1 LAST CDS_LMAN_SYM_OUTLINE -25,50,25,-50
J 2
(-650 2950);
DISPLAY 0.468085 (-650 2950);
PAINT GREEN (-650 2950);
DISPLAY INVISIBLE (-650 2950);
FORCEPROP 1 LAST PATH I70
J 2
(-650 2950);
DISPLAY 0.723404 (-650 2950);
DISPLAY INVISIBLE (-650 2950);
FORCEPROP 1 LAST $LOCATION C844
J 0
(-400 3025);
DISPLAY 1.021277 (-400 3025);
DISPLAY INVISIBLE (-400 3025);
FORCEPROP 2 LAST CDS_LOCATION C844
J 0
(-400 3025);
DISPLAY 1.021277 (-400 3025);
DISPLAY INVISIBLE (-400 3025);
FORCEPROP 2 LAST $SEC 1
J 2
(-475 3025);
DISPLAY 0.680851 (-475 3025);
PAINT MONO (-475 3025);
DISPLAY INVISIBLE (-475 3025);
FORCEPROP 2 LAST CDS_SEC 1
J 2
(-475 3025);
DISPLAY 0.680851 (-475 3025);
DISPLAY INVISIBLE (-475 3025);
FORCEADD TAP..1
(-100 2150);
FORCEPROP 3 LASTPIN (-150 2150) SIG_NAME P5E_CPU0_PE1_TX_C_DN<8>
J 0
(-140 2160);
DISPLAY 0.659574 (-140 2160);
PAINT MONO (-140 2160);
DISPLAY INVISIBLE (-140 2160);
FORCEPROP 1 LASTPIN (-150 2150) BN 8
J 0
(-162 2158);
DISPLAY 0.680851 (-162 2158);
PAINT GREEN (-162 2158);
FORCEPROP 2 LAST CDS_LIB standard
J 0
(-100 2150);
DISPLAY INVISIBLE (-100 2150);
FORCEPROP 1 LAST BODY_TYPE PLUMBING
J 0
(-100 2200);
DISPLAY 0.872340 (-100 2200);
PAINT GREEN (-100 2200);
DISPLAY INVISIBLE (-100 2200);
FORCEPROP 1 LAST HDL_TAP TRUE
J 0
(225 2025);
DISPLAY 0.872340 (225 2025);
DISPLAY INVISIBLE (225 2025);
FORCEPROP 1 LAST PATH I71
J 0
(-102 2150);
DISPLAY 0.872340 (-102 2150);
PAINT GREEN (-102 2150);
DISPLAY INVISIBLE (-102 2150);
FORCEADD TAP..1
(-100 2350);
FORCEPROP 3 LASTPIN (-150 2350) SIG_NAME P5E_CPU0_PE1_TX_C_DN<9>
J 0
(-140 2360);
DISPLAY 0.659574 (-140 2360);
PAINT MONO (-140 2360);
DISPLAY INVISIBLE (-140 2360);
FORCEPROP 1 LASTPIN (-150 2350) BN 9
J 0
(-162 2358);
DISPLAY 0.680851 (-162 2358);
PAINT GREEN (-162 2358);
FORCEPROP 2 LAST CDS_LIB standard
J 0
(-100 2350);
DISPLAY INVISIBLE (-100 2350);
FORCEPROP 1 LAST BODY_TYPE PLUMBING
J 0
(-100 2400);
DISPLAY 0.872340 (-100 2400);
PAINT GREEN (-100 2400);
DISPLAY INVISIBLE (-100 2400);
FORCEPROP 1 LAST HDL_TAP TRUE
J 0
(225 2225);
DISPLAY 0.872340 (225 2225);
DISPLAY INVISIBLE (225 2225);
FORCEPROP 1 LAST PATH I72
J 0
(-102 2350);
DISPLAY 0.872340 (-102 2350);
PAINT GREEN (-102 2350);
DISPLAY INVISIBLE (-102 2350);
FORCEADD TAP..1
(-100 2550);
FORCEPROP 3 LASTPIN (-150 2550) SIG_NAME P5E_CPU0_PE1_TX_C_DN<10>
J 0
(-140 2560);
DISPLAY 0.659574 (-140 2560);
PAINT MONO (-140 2560);
DISPLAY INVISIBLE (-140 2560);
FORCEPROP 1 LASTPIN (-150 2550) BN 10
J 0
(-162 2558);
DISPLAY 0.680851 (-162 2558);
PAINT GREEN (-162 2558);
FORCEPROP 2 LAST CDS_LIB standard
J 0
(-100 2550);
DISPLAY INVISIBLE (-100 2550);
FORCEPROP 1 LAST BODY_TYPE PLUMBING
J 0
(-100 2600);
DISPLAY 0.872340 (-100 2600);
PAINT GREEN (-100 2600);
DISPLAY INVISIBLE (-100 2600);
FORCEPROP 1 LAST HDL_TAP TRUE
J 0
(225 2425);
DISPLAY 0.872340 (225 2425);
DISPLAY INVISIBLE (225 2425);
FORCEPROP 1 LAST PATH I73
J 0
(-102 2550);
DISPLAY 0.872340 (-102 2550);
PAINT GREEN (-102 2550);
DISPLAY INVISIBLE (-102 2550);
FORCEADD TAP..1
(-100 2750);
FORCEPROP 3 LASTPIN (-150 2750) SIG_NAME P5E_CPU0_PE1_TX_C_DN<11>
J 0
(-140 2760);
DISPLAY 0.659574 (-140 2760);
PAINT MONO (-140 2760);
DISPLAY INVISIBLE (-140 2760);
FORCEPROP 1 LASTPIN (-150 2750) BN 11
J 0
(-162 2758);
DISPLAY 0.680851 (-162 2758);
PAINT GREEN (-162 2758);
FORCEPROP 2 LAST CDS_LIB standard
J 0
(-100 2750);
DISPLAY INVISIBLE (-100 2750);
FORCEPROP 1 LAST BODY_TYPE PLUMBING
J 0
(-100 2800);
DISPLAY 0.872340 (-100 2800);
PAINT GREEN (-100 2800);
DISPLAY INVISIBLE (-100 2800);
FORCEPROP 1 LAST HDL_TAP TRUE
J 0
(225 2625);
DISPLAY 0.872340 (225 2625);
DISPLAY INVISIBLE (225 2625);
FORCEPROP 1 LAST PATH I74
J 0
(-102 2750);
DISPLAY 0.872340 (-102 2750);
PAINT GREEN (-102 2750);
DISPLAY INVISIBLE (-102 2750);
FORCEADD TAP..1
(-100 2950);
FORCEPROP 3 LASTPIN (-150 2950) SIG_NAME P5E_CPU0_PE1_TX_C_DN<12>
J 0
(-140 2960);
DISPLAY 0.659574 (-140 2960);
PAINT MONO (-140 2960);
DISPLAY INVISIBLE (-140 2960);
FORCEPROP 1 LASTPIN (-150 2950) BN 12
J 0
(-162 2958);
DISPLAY 0.680851 (-162 2958);
PAINT GREEN (-162 2958);
FORCEPROP 2 LAST CDS_LIB standard
J 0
(-100 2950);
DISPLAY INVISIBLE (-100 2950);
FORCEPROP 1 LAST BODY_TYPE PLUMBING
J 0
(-100 3000);
DISPLAY 0.872340 (-100 3000);
PAINT GREEN (-100 3000);
DISPLAY INVISIBLE (-100 3000);
FORCEPROP 1 LAST HDL_TAP TRUE
J 0
(225 2825);
DISPLAY 0.872340 (225 2825);
DISPLAY INVISIBLE (225 2825);
FORCEPROP 1 LAST PATH I75
J 0
(-102 2950);
DISPLAY 0.872340 (-102 2950);
PAINT GREEN (-102 2950);
DISPLAY INVISIBLE (-102 2950);
FORCEADD Q_CAP_DIFFBUS..2
R 2
(-650 3150);
FORCEPROP 1 LAST PART_NUMBER SP_CH4221MEE01
J 2
(-766 3238);
DISPLAY 0.574468 (-766 3238);
PAINT GREEN (-766 3238);
DISPLAY INVISIBLE (-766 3238);
FORCEPROP 2 LAST VALUE DIFF BUS_0.22UF
J 2
(-800 3150);
DISPLAY 0.553191 (-800 3150);
FORCEPROP 1 LAST $LOCATION C842
J 2
(-416 3167);
DISPLAY 0.723404 (-416 3167);
PAINT GREEN (-416 3167);
FORCEPROP 2 LASTPIN (-575 3150) $PN 1
J 0
(-565 3160);
DISPLAY 0.808511 (-565 3160);
FORCEPROP 2 LASTPIN (-725 3150) $PN 2
J 2
(-735 3160);
DISPLAY 0.808511 (-735 3160);
FORCEPROP 2 LAST TOLERANCE 20%
J 2
(-725 3200);
DISPLAY 0.553191 (-725 3200);
DISPLAY INVISIBLE (-725 3200);
FORCEPROP 2 LAST PACK_TYPE C0201
J 2
(-825 3200);
DISPLAY 0.553191 (-825 3200);
DISPLAY INVISIBLE (-825 3200);
FORCEPROP 1 LAST MATERIAL X6S
J 2
(-641 3229);
DISPLAY 0.574468 (-641 3229);
PAINT GREEN (-641 3229);
DISPLAY INVISIBLE (-641 3229);
FORCEPROP 2 LAST VOLTAGE 6.3V
J 2
(-1000 3200);
DISPLAY 0.553191 (-1000 3200);
DISPLAY INVISIBLE (-1000 3200);
FORCEPROP 1 LAST PIN_NAMES_ROTATE TRUE
J 2
(-650 3150);
DISPLAY 0.489362 (-650 3150);
PAINT GREEN (-650 3150);
DISPLAY INVISIBLE (-650 3150);
FORCEPROP 2 LAST CDS_LIB pure_quanta
J 2
(-650 3150);
DISPLAY INVISIBLE (-650 3150);
FORCEPROP 1 LAST CDS_LMAN_SYM_OUTLINE -25,50,25,-50
J 2
(-650 3150);
DISPLAY 0.468085 (-650 3150);
PAINT GREEN (-650 3150);
DISPLAY INVISIBLE (-650 3150);
FORCEPROP 1 LAST PATH I76
J 2
(-650 3150);
DISPLAY 0.723404 (-650 3150);
DISPLAY INVISIBLE (-650 3150);
FORCEPROP 1 LAST $LOCATION C842
J 0
(-400 3225);
DISPLAY 1.021277 (-400 3225);
DISPLAY INVISIBLE (-400 3225);
FORCEPROP 2 LAST CDS_LOCATION C842
J 0
(-400 3225);
DISPLAY 1.021277 (-400 3225);
DISPLAY INVISIBLE (-400 3225);
FORCEPROP 2 LAST $SEC 1
J 2
(-475 3225);
DISPLAY 0.680851 (-475 3225);
PAINT MONO (-475 3225);
DISPLAY INVISIBLE (-475 3225);
FORCEPROP 2 LAST CDS_SEC 1
J 2
(-475 3225);
DISPLAY 0.680851 (-475 3225);
DISPLAY INVISIBLE (-475 3225);
FORCEADD Q_CAP_DIFFBUS..2
R 2
(-650 3100);
FORCEPROP 1 LAST PART_NUMBER SP_CH4221MEE01
J 2
(-766 3188);
DISPLAY 0.574468 (-766 3188);
PAINT GREEN (-766 3188);
DISPLAY INVISIBLE (-766 3188);
FORCEPROP 2 LAST VALUE DIFF BUS_0.22UF
J 2
(-800 3100);
DISPLAY 0.553191 (-800 3100);
FORCEPROP 1 LAST $LOCATION C843
J 2
(-416 3117);
DISPLAY 0.723404 (-416 3117);
PAINT GREEN (-416 3117);
FORCEPROP 2 LASTPIN (-575 3100) $PN 1
J 0
(-565 3110);
DISPLAY 0.808511 (-565 3110);
FORCEPROP 2 LASTPIN (-725 3100) $PN 2
J 2
(-735 3110);
DISPLAY 0.808511 (-735 3110);
FORCEPROP 2 LAST TOLERANCE 20%
J 2
(-725 3150);
DISPLAY 0.553191 (-725 3150);
DISPLAY INVISIBLE (-725 3150);
FORCEPROP 2 LAST PACK_TYPE C0201
J 2
(-825 3150);
DISPLAY 0.553191 (-825 3150);
DISPLAY INVISIBLE (-825 3150);
FORCEPROP 1 LAST MATERIAL X6S
J 2
(-641 3179);
DISPLAY 0.574468 (-641 3179);
PAINT GREEN (-641 3179);
DISPLAY INVISIBLE (-641 3179);
FORCEPROP 2 LAST VOLTAGE 6.3V
J 2
(-1000 3150);
DISPLAY 0.553191 (-1000 3150);
DISPLAY INVISIBLE (-1000 3150);
FORCEPROP 1 LAST PIN_NAMES_ROTATE TRUE
J 2
(-650 3100);
DISPLAY 0.489362 (-650 3100);
PAINT GREEN (-650 3100);
DISPLAY INVISIBLE (-650 3100);
FORCEPROP 2 LAST CDS_LIB pure_quanta
J 2
(-650 3100);
DISPLAY INVISIBLE (-650 3100);
FORCEPROP 1 LAST CDS_LMAN_SYM_OUTLINE -25,50,25,-50
J 2
(-650 3100);
DISPLAY 0.468085 (-650 3100);
PAINT GREEN (-650 3100);
DISPLAY INVISIBLE (-650 3100);
FORCEPROP 1 LAST PATH I77
J 2
(-650 3100);
DISPLAY 0.723404 (-650 3100);
DISPLAY INVISIBLE (-650 3100);
FORCEPROP 1 LAST $LOCATION C843
J 0
(-400 3175);
DISPLAY 1.021277 (-400 3175);
DISPLAY INVISIBLE (-400 3175);
FORCEPROP 2 LAST CDS_LOCATION C843
J 0
(-400 3175);
DISPLAY 1.021277 (-400 3175);
DISPLAY INVISIBLE (-400 3175);
FORCEPROP 2 LAST $SEC 1
J 2
(-475 3175);
DISPLAY 0.680851 (-475 3175);
PAINT MONO (-475 3175);
DISPLAY INVISIBLE (-475 3175);
FORCEPROP 2 LAST CDS_SEC 1
J 2
(-475 3175);
DISPLAY 0.680851 (-475 3175);
DISPLAY INVISIBLE (-475 3175);
FORCEADD Q_CAP_DIFFBUS..2
R 2
(-650 3300);
FORCEPROP 1 LAST PART_NUMBER SP_CH4221MEE01
J 2
(-766 3388);
DISPLAY 0.574468 (-766 3388);
PAINT GREEN (-766 3388);
DISPLAY INVISIBLE (-766 3388);
FORCEPROP 2 LAST VALUE DIFF BUS_0.22UF
J 2
(-800 3300);
DISPLAY 0.553191 (-800 3300);
FORCEPROP 1 LAST $LOCATION C841
J 2
(-416 3317);
DISPLAY 0.723404 (-416 3317);
PAINT GREEN (-416 3317);
FORCEPROP 2 LASTPIN (-575 3300) $PN 1
J 0
(-565 3310);
DISPLAY 0.808511 (-565 3310);
FORCEPROP 2 LASTPIN (-725 3300) $PN 2
J 2
(-735 3310);
DISPLAY 0.808511 (-735 3310);
FORCEPROP 2 LAST TOLERANCE 20%
J 2
(-725 3350);
DISPLAY 0.553191 (-725 3350);
DISPLAY INVISIBLE (-725 3350);
FORCEPROP 2 LAST PACK_TYPE C0201
J 2
(-825 3350);
DISPLAY 0.553191 (-825 3350);
DISPLAY INVISIBLE (-825 3350);
FORCEPROP 1 LAST MATERIAL X6S
J 2
(-641 3379);
DISPLAY 0.574468 (-641 3379);
PAINT GREEN (-641 3379);
DISPLAY INVISIBLE (-641 3379);
FORCEPROP 2 LAST VOLTAGE 6.3V
J 2
(-1000 3350);
DISPLAY 0.553191 (-1000 3350);
DISPLAY INVISIBLE (-1000 3350);
FORCEPROP 1 LAST PIN_NAMES_ROTATE TRUE
J 2
(-650 3300);
DISPLAY 0.489362 (-650 3300);
PAINT GREEN (-650 3300);
DISPLAY INVISIBLE (-650 3300);
FORCEPROP 2 LAST CDS_LIB pure_quanta
J 2
(-650 3300);
DISPLAY INVISIBLE (-650 3300);
FORCEPROP 1 LAST CDS_LMAN_SYM_OUTLINE -25,50,25,-50
J 2
(-650 3300);
DISPLAY 0.468085 (-650 3300);
PAINT GREEN (-650 3300);
DISPLAY INVISIBLE (-650 3300);
FORCEPROP 1 LAST PATH I78
J 2
(-650 3300);
DISPLAY 0.723404 (-650 3300);
DISPLAY INVISIBLE (-650 3300);
FORCEPROP 1 LAST $LOCATION C841
J 0
(-400 3375);
DISPLAY 1.021277 (-400 3375);
DISPLAY INVISIBLE (-400 3375);
FORCEPROP 2 LAST CDS_LOCATION C841
J 0
(-400 3375);
DISPLAY 1.021277 (-400 3375);
DISPLAY INVISIBLE (-400 3375);
FORCEPROP 2 LAST $SEC 1
J 2
(-475 3375);
DISPLAY 0.680851 (-475 3375);
PAINT MONO (-475 3375);
DISPLAY INVISIBLE (-475 3375);
FORCEPROP 2 LAST CDS_SEC 1
J 2
(-475 3375);
DISPLAY 0.680851 (-475 3375);
DISPLAY INVISIBLE (-475 3375);
FORCEADD Q_CAP_DIFFBUS..2
R 2
(-650 3350);
FORCEPROP 1 LAST PART_NUMBER SP_CH4221MEE01
J 2
(-766 3438);
DISPLAY 0.574468 (-766 3438);
PAINT GREEN (-766 3438);
DISPLAY INVISIBLE (-766 3438);
FORCEPROP 2 LAST VALUE DIFF BUS_0.22UF
J 2
(-800 3350);
DISPLAY 0.553191 (-800 3350);
FORCEPROP 1 LAST $LOCATION C840
J 2
(-416 3367);
DISPLAY 0.723404 (-416 3367);
PAINT GREEN (-416 3367);
FORCEPROP 2 LASTPIN (-575 3350) $PN 1
J 0
(-565 3360);
DISPLAY 0.808511 (-565 3360);
FORCEPROP 2 LASTPIN (-725 3350) $PN 2
J 2
(-735 3360);
DISPLAY 0.808511 (-735 3360);
FORCEPROP 2 LAST TOLERANCE 20%
J 2
(-725 3400);
DISPLAY 0.553191 (-725 3400);
DISPLAY INVISIBLE (-725 3400);
FORCEPROP 2 LAST PACK_TYPE C0201
J 2
(-825 3400);
DISPLAY 0.553191 (-825 3400);
DISPLAY INVISIBLE (-825 3400);
FORCEPROP 1 LAST MATERIAL X6S
J 2
(-641 3429);
DISPLAY 0.574468 (-641 3429);
PAINT GREEN (-641 3429);
DISPLAY INVISIBLE (-641 3429);
FORCEPROP 2 LAST VOLTAGE 6.3V
J 2
(-1000 3400);
DISPLAY 0.553191 (-1000 3400);
DISPLAY INVISIBLE (-1000 3400);
FORCEPROP 1 LAST PIN_NAMES_ROTATE TRUE
J 2
(-650 3350);
DISPLAY 0.489362 (-650 3350);
PAINT GREEN (-650 3350);
DISPLAY INVISIBLE (-650 3350);
FORCEPROP 2 LAST CDS_LIB pure_quanta
J 2
(-650 3350);
DISPLAY INVISIBLE (-650 3350);
FORCEPROP 1 LAST CDS_LMAN_SYM_OUTLINE -25,50,25,-50
J 2
(-650 3350);
DISPLAY 0.468085 (-650 3350);
PAINT GREEN (-650 3350);
DISPLAY INVISIBLE (-650 3350);
FORCEPROP 1 LAST PATH I79
J 2
(-650 3350);
DISPLAY 0.723404 (-650 3350);
DISPLAY INVISIBLE (-650 3350);
FORCEPROP 1 LAST $LOCATION C840
J 0
(-400 3425);
DISPLAY 1.021277 (-400 3425);
DISPLAY INVISIBLE (-400 3425);
FORCEPROP 2 LAST CDS_LOCATION C840
J 0
(-400 3425);
DISPLAY 1.021277 (-400 3425);
DISPLAY INVISIBLE (-400 3425);
FORCEPROP 2 LAST $SEC 1
J 2
(-475 3425);
DISPLAY 0.680851 (-475 3425);
PAINT MONO (-475 3425);
DISPLAY INVISIBLE (-475 3425);
FORCEPROP 2 LAST CDS_SEC 1
J 2
(-475 3425);
DISPLAY 0.680851 (-475 3425);
DISPLAY INVISIBLE (-475 3425);
FORCEADD TAP..1
R 2
(-1625 725);
FORCEPROP 3 LASTPIN (-1575 725) SIG_NAME P5E_CPU0_PE1_TX_DP<3>
J 0
(-1565 735);
DISPLAY 0.659574 (-1565 735);
PAINT MONO (-1565 735);
DISPLAY INVISIBLE (-1565 735);
FORCEPROP 1 LASTPIN (-1575 725) BN 3
J 2
(-1563 733);
DISPLAY 0.680851 (-1563 733);
PAINT GREEN (-1563 733);
FORCEPROP 2 LAST CDS_LIB standard
J 0
(-1625 725);
DISPLAY INVISIBLE (-1625 725);
FORCEPROP 1 LAST BODY_TYPE PLUMBING
J 2
(-1625 775);
DISPLAY 0.872340 (-1625 775);
PAINT GREEN (-1625 775);
DISPLAY INVISIBLE (-1625 775);
FORCEPROP 1 LAST HDL_TAP TRUE
J 2
(-1950 600);
DISPLAY 0.872340 (-1950 600);
DISPLAY INVISIBLE (-1950 600);
FORCEPROP 1 LAST PATH I8
J 2
(-1623 725);
DISPLAY 0.872340 (-1623 725);
PAINT GREEN (-1623 725);
DISPLAY INVISIBLE (-1623 725);
FORCEADD Q_CAP_DIFFBUS..2
R 2
(-650 3550);
FORCEPROP 1 LAST PART_NUMBER SP_CH4221MEE01
J 2
(-466 3638);
DISPLAY 0.574468 (-466 3638);
PAINT GREEN (-466 3638);
DISPLAY INVISIBLE (-466 3638);
FORCEPROP 2 LAST VALUE DIFF BUS_0.22UF
J 2
(-800 3550);
DISPLAY 0.553191 (-800 3550);
FORCEPROP 2 LAST PACK_TYPE C0201
J 2
(-700 3700);
DISPLAY 0.553191 (-700 3700);
PAINT GREEN (-700 3700);
FORCEPROP 2 LAST TOLERANCE 20%
J 2
(-600 3700);
DISPLAY 0.553191 (-600 3700);
PAINT GREEN (-600 3700);
FORCEPROP 1 LAST MATERIAL X6S
J 2
(-741 3754);
DISPLAY 0.574468 (-741 3754);
PAINT GREEN (-741 3754);
FORCEPROP 2 LAST VOLTAGE 6.3V
J 2
(-475 3700);
DISPLAY 0.553191 (-475 3700);
PAINT GREEN (-475 3700);
FORCEPROP 1 LAST $LOCATION C838
J 2
(-416 3567);
DISPLAY 0.723404 (-416 3567);
PAINT GREEN (-416 3567);
FORCEPROP 2 LASTPIN (-575 3550) $PN 1
J 0
(-565 3560);
DISPLAY 0.808511 (-565 3560);
FORCEPROP 2 LASTPIN (-725 3550) $PN 2
J 2
(-735 3560);
DISPLAY 0.808511 (-735 3560);
FORCEPROP 1 LAST PIN_NAMES_ROTATE TRUE
J 2
(-650 3550);
DISPLAY 0.489362 (-650 3550);
PAINT GREEN (-650 3550);
DISPLAY INVISIBLE (-650 3550);
FORCEPROP 1 LAST CDS_LMAN_SYM_OUTLINE -25,50,25,-50
J 2
(-650 3550);
DISPLAY 0.468085 (-650 3550);
PAINT GREEN (-650 3550);
DISPLAY INVISIBLE (-650 3550);
FORCEPROP 2 LAST CDS_LIB pure_quanta
J 2
(-650 3550);
DISPLAY INVISIBLE (-650 3550);
FORCEPROP 1 LAST PATH I80
J 2
(-650 3550);
DISPLAY 0.723404 (-650 3550);
DISPLAY INVISIBLE (-650 3550);
FORCEPROP 1 LAST $LOCATION C838
J 0
(-400 3625);
DISPLAY 1.021277 (-400 3625);
DISPLAY INVISIBLE (-400 3625);
FORCEPROP 2 LAST CDS_LOCATION C838
J 0
(-725 3800);
DISPLAY 1.021277 (-725 3800);
DISPLAY INVISIBLE (-725 3800);
FORCEPROP 2 LAST $SEC 1
J 2
(-475 3625);
DISPLAY 0.680851 (-475 3625);
PAINT MONO (-475 3625);
DISPLAY INVISIBLE (-475 3625);
FORCEPROP 2 LAST CDS_SEC 1
J 2
(-475 3625);
DISPLAY 0.680851 (-475 3625);
DISPLAY INVISIBLE (-475 3625);
FORCEADD Q_CAP_DIFFBUS..2
R 2
(-650 3500);
FORCEPROP 1 LAST PART_NUMBER SP_CH4221MEE01
J 2
(-766 3588);
DISPLAY 0.574468 (-766 3588);
PAINT GREEN (-766 3588);
DISPLAY INVISIBLE (-766 3588);
FORCEPROP 2 LAST VALUE DIFF BUS_0.22UF
J 2
(-800 3500);
DISPLAY 0.553191 (-800 3500);
FORCEPROP 1 LAST $LOCATION C839
J 2
(-416 3517);
DISPLAY 0.723404 (-416 3517);
PAINT GREEN (-416 3517);
FORCEPROP 2 LASTPIN (-575 3500) $PN 1
J 0
(-565 3510);
DISPLAY 0.808511 (-565 3510);
FORCEPROP 2 LASTPIN (-725 3500) $PN 2
J 2
(-735 3510);
DISPLAY 0.808511 (-735 3510);
FORCEPROP 2 LAST TOLERANCE 20%
J 2
(-725 3550);
DISPLAY 0.553191 (-725 3550);
DISPLAY INVISIBLE (-725 3550);
FORCEPROP 2 LAST PACK_TYPE C0201
J 2
(-825 3550);
DISPLAY 0.553191 (-825 3550);
DISPLAY INVISIBLE (-825 3550);
FORCEPROP 1 LAST MATERIAL X6S
J 2
(-641 3579);
DISPLAY 0.574468 (-641 3579);
PAINT GREEN (-641 3579);
DISPLAY INVISIBLE (-641 3579);
FORCEPROP 2 LAST VOLTAGE 6.3V
J 2
(-1000 3550);
DISPLAY 0.553191 (-1000 3550);
DISPLAY INVISIBLE (-1000 3550);
FORCEPROP 1 LAST PIN_NAMES_ROTATE TRUE
J 2
(-650 3500);
DISPLAY 0.489362 (-650 3500);
PAINT GREEN (-650 3500);
DISPLAY INVISIBLE (-650 3500);
FORCEPROP 2 LAST CDS_LIB pure_quanta
J 2
(-650 3500);
DISPLAY INVISIBLE (-650 3500);
FORCEPROP 1 LAST CDS_LMAN_SYM_OUTLINE -25,50,25,-50
J 2
(-650 3500);
DISPLAY 0.468085 (-650 3500);
PAINT GREEN (-650 3500);
DISPLAY INVISIBLE (-650 3500);
FORCEPROP 1 LAST PATH I81
J 2
(-650 3500);
DISPLAY 0.723404 (-650 3500);
DISPLAY INVISIBLE (-650 3500);
FORCEPROP 1 LAST $LOCATION C839
J 0
(-400 3575);
DISPLAY 1.021277 (-400 3575);
DISPLAY INVISIBLE (-400 3575);
FORCEPROP 2 LAST CDS_LOCATION C839
J 0
(-400 3575);
DISPLAY 1.021277 (-400 3575);
DISPLAY INVISIBLE (-400 3575);
FORCEPROP 2 LAST $SEC 1
J 2
(-475 3575);
DISPLAY 0.680851 (-475 3575);
PAINT MONO (-475 3575);
DISPLAY INVISIBLE (-475 3575);
FORCEPROP 2 LAST CDS_SEC 1
J 2
(-475 3575);
DISPLAY 0.680851 (-475 3575);
DISPLAY INVISIBLE (-475 3575);
FORCEADD TAP..1
(-100 3550);
FORCEPROP 3 LASTPIN (-150 3550) SIG_NAME P5E_CPU0_PE1_TX_C_DN<15>
J 0
(-140 3560);
DISPLAY 0.659574 (-140 3560);
PAINT MONO (-140 3560);
DISPLAY INVISIBLE (-140 3560);
FORCEPROP 1 LASTPIN (-150 3550) BN 15
J 0
(-162 3558);
DISPLAY 0.680851 (-162 3558);
PAINT GREEN (-162 3558);
FORCEPROP 2 LAST CDS_LIB standard
J 0
(-100 3550);
DISPLAY INVISIBLE (-100 3550);
FORCEPROP 1 LAST BODY_TYPE PLUMBING
J 0
(-100 3600);
DISPLAY 0.872340 (-100 3600);
PAINT GREEN (-100 3600);
DISPLAY INVISIBLE (-100 3600);
FORCEPROP 1 LAST HDL_TAP TRUE
J 0
(225 3425);
DISPLAY 0.872340 (225 3425);
DISPLAY INVISIBLE (225 3425);
FORCEPROP 1 LAST PATH I82
J 0
(-102 3550);
DISPLAY 0.872340 (-102 3550);
PAINT GREEN (-102 3550);
DISPLAY INVISIBLE (-102 3550);
FORCEADD TAP..1
(-100 3350);
FORCEPROP 3 LASTPIN (-150 3350) SIG_NAME P5E_CPU0_PE1_TX_C_DN<14>
J 0
(-140 3360);
DISPLAY 0.659574 (-140 3360);
PAINT MONO (-140 3360);
DISPLAY INVISIBLE (-140 3360);
FORCEPROP 1 LASTPIN (-150 3350) BN 14
J 0
(-162 3358);
DISPLAY 0.680851 (-162 3358);
PAINT GREEN (-162 3358);
FORCEPROP 2 LAST CDS_LIB standard
J 0
(-100 3350);
DISPLAY INVISIBLE (-100 3350);
FORCEPROP 1 LAST BODY_TYPE PLUMBING
J 0
(-100 3400);
DISPLAY 0.872340 (-100 3400);
PAINT GREEN (-100 3400);
DISPLAY INVISIBLE (-100 3400);
FORCEPROP 1 LAST HDL_TAP TRUE
J 0
(225 3225);
DISPLAY 0.872340 (225 3225);
DISPLAY INVISIBLE (225 3225);
FORCEPROP 1 LAST PATH I83
J 0
(-102 3350);
DISPLAY 0.872340 (-102 3350);
PAINT GREEN (-102 3350);
DISPLAY INVISIBLE (-102 3350);
FORCEADD TAP..1
(-100 3150);
FORCEPROP 3 LASTPIN (-150 3150) SIG_NAME P5E_CPU0_PE1_TX_C_DN<13>
J 0
(-140 3160);
DISPLAY 0.659574 (-140 3160);
PAINT MONO (-140 3160);
DISPLAY INVISIBLE (-140 3160);
FORCEPROP 1 LASTPIN (-150 3150) BN 13
J 0
(-162 3158);
DISPLAY 0.680851 (-162 3158);
PAINT GREEN (-162 3158);
FORCEPROP 2 LAST CDS_LIB standard
J 0
(-100 3150);
DISPLAY INVISIBLE (-100 3150);
FORCEPROP 1 LAST BODY_TYPE PLUMBING
J 0
(-100 3200);
DISPLAY 0.872340 (-100 3200);
PAINT GREEN (-100 3200);
DISPLAY INVISIBLE (-100 3200);
FORCEPROP 1 LAST HDL_TAP TRUE
J 0
(225 3025);
DISPLAY 0.872340 (225 3025);
DISPLAY INVISIBLE (225 3025);
FORCEPROP 1 LAST PATH I84
J 0
(-102 3150);
DISPLAY 0.872340 (-102 3150);
PAINT GREEN (-102 3150);
DISPLAY INVISIBLE (-102 3150);
FORCEADD TAP..1
(100 125);
FORCEPROP 3 LASTPIN (50 125) SIG_NAME P5E_CPU0_PE1_TX_C_DP<0>
J 0
(60 135);
DISPLAY 0.659574 (60 135);
PAINT MONO (60 135);
DISPLAY INVISIBLE (60 135);
FORCEPROP 1 LASTPIN (50 125) BN 0
J 0
(38 133);
DISPLAY 0.680851 (38 133);
PAINT GREEN (38 133);
FORCEPROP 2 LAST CDS_LIB standard
J 0
(100 125);
DISPLAY INVISIBLE (100 125);
FORCEPROP 1 LAST BODY_TYPE PLUMBING
J 0
(100 175);
DISPLAY 0.872340 (100 175);
PAINT GREEN (100 175);
DISPLAY INVISIBLE (100 175);
FORCEPROP 1 LAST HDL_TAP TRUE
J 0
(425 0);
DISPLAY 0.872340 (425 0);
DISPLAY INVISIBLE (425 0);
FORCEPROP 1 LAST PATH I85
J 0
(98 125);
DISPLAY 0.872340 (98 125);
PAINT GREEN (98 125);
DISPLAY INVISIBLE (98 125);
FORCEADD TAP..1
(100 325);
FORCEPROP 3 LASTPIN (50 325) SIG_NAME P5E_CPU0_PE1_TX_C_DP<1>
J 0
(60 335);
DISPLAY 0.659574 (60 335);
PAINT MONO (60 335);
DISPLAY INVISIBLE (60 335);
FORCEPROP 1 LASTPIN (50 325) BN 1
J 0
(38 333);
DISPLAY 0.680851 (38 333);
PAINT GREEN (38 333);
FORCEPROP 2 LAST CDS_LIB standard
J 0
(100 325);
DISPLAY INVISIBLE (100 325);
FORCEPROP 1 LAST BODY_TYPE PLUMBING
J 0
(100 375);
DISPLAY 0.872340 (100 375);
PAINT GREEN (100 375);
DISPLAY INVISIBLE (100 375);
FORCEPROP 1 LAST HDL_TAP TRUE
J 0
(425 200);
DISPLAY 0.872340 (425 200);
DISPLAY INVISIBLE (425 200);
FORCEPROP 1 LAST PATH I86
J 0
(98 325);
DISPLAY 0.872340 (98 325);
PAINT GREEN (98 325);
DISPLAY INVISIBLE (98 325);
FORCEADD TAP..1
(100 525);
FORCEPROP 3 LASTPIN (50 525) SIG_NAME P5E_CPU0_PE1_TX_C_DP<2>
J 0
(60 535);
DISPLAY 0.659574 (60 535);
PAINT MONO (60 535);
DISPLAY INVISIBLE (60 535);
FORCEPROP 1 LASTPIN (50 525) BN 2
J 0
(38 533);
DISPLAY 0.680851 (38 533);
PAINT GREEN (38 533);
FORCEPROP 2 LAST CDS_LIB standard
J 0
(100 525);
DISPLAY INVISIBLE (100 525);
FORCEPROP 1 LAST BODY_TYPE PLUMBING
J 0
(100 575);
DISPLAY 0.872340 (100 575);
PAINT GREEN (100 575);
DISPLAY INVISIBLE (100 575);
FORCEPROP 1 LAST HDL_TAP TRUE
J 0
(425 400);
DISPLAY 0.872340 (425 400);
DISPLAY INVISIBLE (425 400);
FORCEPROP 1 LAST PATH I87
J 0
(98 525);
DISPLAY 0.872340 (98 525);
PAINT GREEN (98 525);
DISPLAY INVISIBLE (98 525);
FORCEADD TAP..1
(100 725);
FORCEPROP 3 LASTPIN (50 725) SIG_NAME P5E_CPU0_PE1_TX_C_DP<3>
J 0
(60 735);
DISPLAY 0.659574 (60 735);
PAINT MONO (60 735);
DISPLAY INVISIBLE (60 735);
FORCEPROP 1 LASTPIN (50 725) BN 3
J 0
(38 733);
DISPLAY 0.680851 (38 733);
PAINT GREEN (38 733);
FORCEPROP 2 LAST CDS_LIB standard
J 0
(100 725);
DISPLAY INVISIBLE (100 725);
FORCEPROP 1 LAST BODY_TYPE PLUMBING
J 0
(100 775);
DISPLAY 0.872340 (100 775);
PAINT GREEN (100 775);
DISPLAY INVISIBLE (100 775);
FORCEPROP 1 LAST HDL_TAP TRUE
J 0
(425 600);
DISPLAY 0.872340 (425 600);
DISPLAY INVISIBLE (425 600);
FORCEPROP 1 LAST PATH I88
J 0
(98 725);
DISPLAY 0.872340 (98 725);
PAINT GREEN (98 725);
DISPLAY INVISIBLE (98 725);
FORCEADD TAP..1
(100 925);
FORCEPROP 3 LASTPIN (50 925) SIG_NAME P5E_CPU0_PE1_TX_C_DP<4>
J 0
(60 935);
DISPLAY 0.659574 (60 935);
PAINT MONO (60 935);
DISPLAY INVISIBLE (60 935);
FORCEPROP 1 LASTPIN (50 925) BN 4
J 0
(38 933);
DISPLAY 0.680851 (38 933);
PAINT GREEN (38 933);
FORCEPROP 2 LAST CDS_LIB standard
J 0
(100 925);
DISPLAY INVISIBLE (100 925);
FORCEPROP 1 LAST BODY_TYPE PLUMBING
J 0
(100 975);
DISPLAY 0.872340 (100 975);
PAINT GREEN (100 975);
DISPLAY INVISIBLE (100 975);
FORCEPROP 1 LAST HDL_TAP TRUE
J 0
(425 800);
DISPLAY 0.872340 (425 800);
DISPLAY INVISIBLE (425 800);
FORCEPROP 1 LAST PATH I89
J 0
(98 925);
DISPLAY 0.872340 (98 925);
PAINT GREEN (98 925);
DISPLAY INVISIBLE (98 925);
FORCEADD TAP..1
R 2
(-1625 925);
FORCEPROP 3 LASTPIN (-1575 925) SIG_NAME P5E_CPU0_PE1_TX_DP<4>
J 0
(-1565 935);
DISPLAY 0.659574 (-1565 935);
PAINT MONO (-1565 935);
DISPLAY INVISIBLE (-1565 935);
FORCEPROP 1 LASTPIN (-1575 925) BN 4
J 2
(-1563 933);
DISPLAY 0.680851 (-1563 933);
PAINT GREEN (-1563 933);
FORCEPROP 2 LAST CDS_LIB standard
J 0
(-1625 925);
DISPLAY INVISIBLE (-1625 925);
FORCEPROP 1 LAST BODY_TYPE PLUMBING
J 2
(-1625 975);
DISPLAY 0.872340 (-1625 975);
PAINT GREEN (-1625 975);
DISPLAY INVISIBLE (-1625 975);
FORCEPROP 1 LAST HDL_TAP TRUE
J 2
(-1950 800);
DISPLAY 0.872340 (-1950 800);
DISPLAY INVISIBLE (-1950 800);
FORCEPROP 1 LAST PATH I9
J 2
(-1623 925);
DISPLAY 0.872340 (-1623 925);
PAINT GREEN (-1623 925);
DISPLAY INVISIBLE (-1623 925);
FORCEADD TAP..1
(100 1125);
FORCEPROP 3 LASTPIN (50 1125) SIG_NAME P5E_CPU0_PE1_TX_C_DP<5>
J 0
(60 1135);
DISPLAY 0.659574 (60 1135);
PAINT MONO (60 1135);
DISPLAY INVISIBLE (60 1135);
FORCEPROP 1 LASTPIN (50 1125) BN 5
J 0
(38 1133);
DISPLAY 0.680851 (38 1133);
PAINT GREEN (38 1133);
FORCEPROP 2 LAST CDS_LIB standard
J 0
(100 1125);
DISPLAY INVISIBLE (100 1125);
FORCEPROP 1 LAST BODY_TYPE PLUMBING
J 0
(100 1175);
DISPLAY 0.872340 (100 1175);
PAINT GREEN (100 1175);
DISPLAY INVISIBLE (100 1175);
FORCEPROP 1 LAST HDL_TAP TRUE
J 0
(425 1000);
DISPLAY 0.872340 (425 1000);
DISPLAY INVISIBLE (425 1000);
FORCEPROP 1 LAST PATH I90
J 0
(98 1125);
DISPLAY 0.872340 (98 1125);
PAINT GREEN (98 1125);
DISPLAY INVISIBLE (98 1125);
FORCEADD TAP..1
(100 1325);
FORCEPROP 3 LASTPIN (50 1325) SIG_NAME P5E_CPU0_PE1_TX_C_DP<6>
J 0
(60 1335);
DISPLAY 0.659574 (60 1335);
PAINT MONO (60 1335);
DISPLAY INVISIBLE (60 1335);
FORCEPROP 1 LASTPIN (50 1325) BN 6
J 0
(38 1333);
DISPLAY 0.680851 (38 1333);
PAINT GREEN (38 1333);
FORCEPROP 2 LAST CDS_LIB standard
J 0
(100 1325);
DISPLAY INVISIBLE (100 1325);
FORCEPROP 1 LAST BODY_TYPE PLUMBING
J 0
(100 1375);
DISPLAY 0.872340 (100 1375);
PAINT GREEN (100 1375);
DISPLAY INVISIBLE (100 1375);
FORCEPROP 1 LAST HDL_TAP TRUE
J 0
(425 1200);
DISPLAY 0.872340 (425 1200);
DISPLAY INVISIBLE (425 1200);
FORCEPROP 1 LAST PATH I91
J 0
(98 1325);
DISPLAY 0.872340 (98 1325);
PAINT GREEN (98 1325);
DISPLAY INVISIBLE (98 1325);
FORCEADD TAP..1
(100 1525);
FORCEPROP 3 LASTPIN (50 1525) SIG_NAME P5E_CPU0_PE1_TX_C_DP<7>
J 0
(60 1535);
DISPLAY 0.659574 (60 1535);
PAINT MONO (60 1535);
DISPLAY INVISIBLE (60 1535);
FORCEPROP 1 LASTPIN (50 1525) BN 7
J 0
(38 1533);
DISPLAY 0.680851 (38 1533);
PAINT GREEN (38 1533);
FORCEPROP 2 LAST CDS_LIB standard
J 0
(100 1525);
DISPLAY INVISIBLE (100 1525);
FORCEPROP 1 LAST BODY_TYPE PLUMBING
J 0
(100 1575);
DISPLAY 0.872340 (100 1575);
PAINT GREEN (100 1575);
DISPLAY INVISIBLE (100 1575);
FORCEPROP 1 LAST HDL_TAP TRUE
J 0
(425 1400);
DISPLAY 0.872340 (425 1400);
DISPLAY INVISIBLE (425 1400);
FORCEPROP 1 LAST PATH I92
J 0
(98 1525);
DISPLAY 0.872340 (98 1525);
PAINT GREEN (98 1525);
DISPLAY INVISIBLE (98 1525);
FORCEADD OFFPAGE..2
(1100 1550);
FORCEPROP 2 LAST $XR0 153 
J 0
(1289 1550);
DISPLAY 0.638298 (1289 1550);
PAINT MONO (1289 1550);
FORCEPROP 2 LAST CDS_LIB standard
J 0
(1100 1550);
DISPLAY INVISIBLE (1100 1550);
FORCEPROP 1 LAST OFFPAGE TRUE
J 0
(1425 1425);
DISPLAY 0.872340 (1425 1425);
DISPLAY INVISIBLE (1425 1425);
FORCEPROP 1 LAST COMMENT_BODY TRUE
J 0
(1055 1455);
DISPLAY 0.872340 (1055 1455);
PAINT GREEN (1055 1455);
DISPLAY INVISIBLE (1055 1455);
FORCEPROP 2 LAST PATH I93
J 0
(1300 1600);
DISPLAY 1.021277 (1300 1600);
DISPLAY INVISIBLE (1300 1600);
FORCEADD OFFPAGE..2
(1100 1600);
FORCEPROP 2 LAST $XR0 153 
J 0
(1289 1600);
DISPLAY 0.638298 (1289 1600);
PAINT MONO (1289 1600);
FORCEPROP 2 LAST CDS_LIB standard
J 0
(1100 1600);
DISPLAY INVISIBLE (1100 1600);
FORCEPROP 1 LAST OFFPAGE TRUE
J 0
(1425 1475);
DISPLAY 0.872340 (1425 1475);
DISPLAY INVISIBLE (1425 1475);
FORCEPROP 1 LAST COMMENT_BODY TRUE
J 0
(1055 1505);
DISPLAY 0.872340 (1055 1505);
PAINT GREEN (1055 1505);
DISPLAY INVISIBLE (1055 1505);
FORCEPROP 2 LAST PATH I94
J 0
(1300 1650);
DISPLAY 1.021277 (1300 1650);
DISPLAY INVISIBLE (1300 1650);
FORCEADD OFFPAGE..1
(1900 1600);
FORCEPROP 2 LAST $XR0 30 
J 0
(1679 1600);
DISPLAY 0.638298 (1679 1600);
PAINT MONO (1679 1600);
FORCEPROP 2 LAST CDS_LIB standard
J 0
(1900 1600);
DISPLAY INVISIBLE (1900 1600);
FORCEPROP 1 LAST OFFPAGE TRUE
J 0
(2225 1475);
DISPLAY 0.872340 (2225 1475);
DISPLAY INVISIBLE (2225 1475);
FORCEPROP 1 LAST COMMENT_BODY TRUE
J 0
(2025 1500);
DISPLAY 0.872340 (2025 1500);
PAINT GREEN (2025 1500);
DISPLAY INVISIBLE (2025 1500);
FORCEPROP 2 LAST PATH I95
J 0
(1650 1650);
DISPLAY 1.021277 (1650 1650);
DISPLAY INVISIBLE (1650 1650);
FORCEADD OFFPAGE..1
(1900 1550);
FORCEPROP 2 LAST $XR0 30 
J 0
(1679 1550);
DISPLAY 0.638298 (1679 1550);
PAINT MONO (1679 1550);
FORCEPROP 2 LAST CDS_LIB standard
J 0
(1900 1550);
DISPLAY INVISIBLE (1900 1550);
FORCEPROP 1 LAST OFFPAGE TRUE
J 0
(2225 1425);
DISPLAY 0.872340 (2225 1425);
DISPLAY INVISIBLE (2225 1425);
FORCEPROP 1 LAST COMMENT_BODY TRUE
J 0
(2025 1450);
DISPLAY 0.872340 (2025 1450);
PAINT GREEN (2025 1450);
DISPLAY INVISIBLE (2025 1450);
FORCEPROP 2 LAST PATH I96
J 0
(1650 1600);
DISPLAY 1.021277 (1650 1600);
DISPLAY INVISIBLE (1650 1600);
FORCEADD TAP..1
(100 2100);
FORCEPROP 3 LASTPIN (50 2100) SIG_NAME P5E_CPU0_PE1_TX_C_DP<8>
J 0
(60 2110);
DISPLAY 0.659574 (60 2110);
PAINT MONO (60 2110);
DISPLAY INVISIBLE (60 2110);
FORCEPROP 1 LASTPIN (50 2100) BN 8
J 0
(38 2108);
DISPLAY 0.680851 (38 2108);
PAINT GREEN (38 2108);
FORCEPROP 2 LAST CDS_LIB standard
J 0
(100 2100);
DISPLAY INVISIBLE (100 2100);
FORCEPROP 1 LAST BODY_TYPE PLUMBING
J 0
(100 2150);
DISPLAY 0.872340 (100 2150);
PAINT GREEN (100 2150);
DISPLAY INVISIBLE (100 2150);
FORCEPROP 1 LAST HDL_TAP TRUE
J 0
(425 1975);
DISPLAY 0.872340 (425 1975);
DISPLAY INVISIBLE (425 1975);
FORCEPROP 1 LAST PATH I97
J 0
(98 2100);
DISPLAY 0.872340 (98 2100);
PAINT GREEN (98 2100);
DISPLAY INVISIBLE (98 2100);
FORCEADD TAP..1
(100 2300);
FORCEPROP 3 LASTPIN (50 2300) SIG_NAME P5E_CPU0_PE1_TX_C_DP<9>
J 0
(60 2310);
DISPLAY 0.659574 (60 2310);
PAINT MONO (60 2310);
DISPLAY INVISIBLE (60 2310);
FORCEPROP 1 LASTPIN (50 2300) BN 9
J 0
(38 2308);
DISPLAY 0.680851 (38 2308);
PAINT GREEN (38 2308);
FORCEPROP 2 LAST CDS_LIB standard
J 0
(100 2300);
DISPLAY INVISIBLE (100 2300);
FORCEPROP 1 LAST BODY_TYPE PLUMBING
J 0
(100 2350);
DISPLAY 0.872340 (100 2350);
PAINT GREEN (100 2350);
DISPLAY INVISIBLE (100 2350);
FORCEPROP 1 LAST HDL_TAP TRUE
J 0
(425 2175);
DISPLAY 0.872340 (425 2175);
DISPLAY INVISIBLE (425 2175);
FORCEPROP 1 LAST PATH I98
J 0
(98 2300);
DISPLAY 0.872340 (98 2300);
PAINT GREEN (98 2300);
DISPLAY INVISIBLE (98 2300);
FORCEADD TAP..1
(100 2500);
FORCEPROP 3 LASTPIN (50 2500) SIG_NAME P5E_CPU0_PE1_TX_C_DP<10>
J 0
(60 2510);
DISPLAY 0.659574 (60 2510);
PAINT MONO (60 2510);
DISPLAY INVISIBLE (60 2510);
FORCEPROP 1 LASTPIN (50 2500) BN 10
J 0
(38 2508);
DISPLAY 0.680851 (38 2508);
PAINT GREEN (38 2508);
FORCEPROP 2 LAST CDS_LIB standard
J 0
(100 2500);
DISPLAY INVISIBLE (100 2500);
FORCEPROP 1 LAST BODY_TYPE PLUMBING
J 0
(100 2550);
DISPLAY 0.872340 (100 2550);
PAINT GREEN (100 2550);
DISPLAY INVISIBLE (100 2550);
FORCEPROP 1 LAST HDL_TAP TRUE
J 0
(425 2375);
DISPLAY 0.872340 (425 2375);
DISPLAY INVISIBLE (425 2375);
FORCEPROP 1 LAST PATH I99
J 0
(98 2500);
DISPLAY 0.872340 (98 2500);
PAINT GREEN (98 2500);
DISPLAY INVISIBLE (98 2500);
FORCEADD QUANTA_TITLE_BLOCK_C..1
(6175 -1700);
FORCEPROP 0 LAST CDS_CON_LAST_MODIFIED Fri Aug 25 14:02:45 2023
J 0
(4290 -1685);
DISPLAY INVISIBLE (4290 -1685);
FORCEPROP 2 LAST CUSTOM_TXT_CDS <XR_PAGE_TITLE>
J 0
(-1715 3550);
DISPLAY 0.638298 (-1715 3550);
PAINT PINK (-1715 3550);
DISPLAY INVISIBLE (-1715 3550);
FORCEPROP 2 LAST CUSTOM_TXT_CDS <CON_LAST_MODIFIED>
J 0
(4290 -1685);
DISPLAY 0.978723 (4290 -1685);
FORCEPROP 2 LAST CUSTOM_TXT_CDS <Q_REV>
J 0
(5991 -1597);
DISPLAY 1.212766 (5991 -1597);
FORCEPROP 2 LAST CUSTOM_TXT_CDS <CON_PAGE_NUM> OF <CON_TOTAL_PAGES>
J 0
(5729 -1682);
DISPLAY 0.978723 (5729 -1682);
FORCEPROP 2 LAST CUSTOM_TXT_CDS <Q_PROJ>
J 0
(3793 -1598);
DISPLAY 1.212766 (3793 -1598);
FORCEPROP 2 LAST CUSTOM_TXT_CDS <Q_NUMBER>
J 0
(4772 -1597);
DISPLAY 1.212766 (4772 -1597);
FORCEPROP 1 LAST CUSTOM_TXT_CDS <NAME_2>
J 0
(3000 -1650);
FORCEPROP 1 LAST CUSTOM_TXT_CDS <NAME_1>
J 0
(3000 -1525);
FORCEPROP 1 LAST Q_TITLE PCIE AC-COUPLE CAPS 2/5
J 0
(-3191 -1674);
DISPLAY 2.446809 (-3191 -1674);
PAINT GREEN (-3191 -1674);
FORCEPROP 1 LAST Q_DEPT 
J 1
(2412 -1651);
DISPLAY 1.957447 (2412 -1651);
PAINT GREEN (2412 -1651);
FORCEPROP 2 LAST CDS_XR_PAGE_TITLE CR-174 : @S9S_MB_2U_LIB.S9S_MB_2U(SCH_1):PAGE174
J 0
(-1715 3550);
DISPLAY 0.638298 (-1715 3550);
PAINT PINK (-1715 3550);
DISPLAY INVISIBLE (-1715 3550);
FORCEPROP 2 LAST PAGE_BORDER TRUE
J 0
(-1715 3550);
DISPLAY 0.638298 (-1715 3550);
PAINT PINK (-1715 3550);
DISPLAY INVISIBLE (-1715 3550);
FORCEPROP 1 LAST COMMENT_BODY TRUE
J 0
(6187 -1713);
DISPLAY 0.978723 (6187 -1713);
PAINT GREEN (6187 -1713);
DISPLAY INVISIBLE (6187 -1713);
FORCEPROP 1 LAST CDS_LMAN_SYM_OUTLINE -9475,6775,100,-125
J 0
(6175 -1700);
DISPLAY 0.468085 (6175 -1700);
PAINT GREEN (6175 -1700);
DISPLAY INVISIBLE (6175 -1700);
FORCEPROP 2 LAST CDS_LIB pure_quanta
J 0
(6175 -1700);
DISPLAY INVISIBLE (6175 -1700);
WIRE 17 -1 (-1675 950)(-1675 1150);
WIRE 17 -1 (-1675 750)(-1675 950);
WIRE 17 -1 (-1675 1150)(-1675 1350);
WIRE 17 -1 (-1675 1350)(-1675 1550);
WIRE 17 -1 (-1675 550)(-1675 750);
WIRE 17 -1 (-1675 350)(-1675 550);
WIRE 17 -1 (-2525 1550)(-1675 1550);
FORCEPROP 2 LAST SIG_NAME P5E_CPU0_PE1_TX_DP<7:0>
J 0
(-2510 1560);
DISPLAY 0.680851 (-2510 1560);
PAINT WHITE (-2510 1560);
WIRE 17 -1 (-1425 800)(-1425 1000);
WIRE 17 -1 (-1425 800)(-1425 600);
WIRE 17 -1 (-1425 1200)(-1425 1000);
WIRE 17 -1 (-1425 1400)(-1425 1200);
WIRE 17 -1 (-1425 600)(-1425 400);
WIRE 17 -1 (-1425 400)(-1425 200);
WIRE 17 -1 (-1425 1600)(-1425 1400);
WIRE 17 -1 (-2525 1600)(-1425 1600);
FORCEPROP 2 LAST SIG_NAME P5E_CPU0_PE1_TX_DN<7:0>
J 0
(-2510 1610);
DISPLAY 0.680851 (-2510 1610);
PAINT WHITE (-2510 1610);
WIRE 17 -1 (-1675 150)(-1675 350);
WIRE 17 -1 (-50 400)(-50 200);
WIRE 17 -1 (-50 600)(-50 400);
WIRE 17 -1 (-50 800)(-50 600);
WIRE 17 -1 (-50 800)(-50 1000);
WIRE 17 -1 (-50 1200)(-50 1000);
WIRE 17 -1 (-50 1400)(-50 1200);
WIRE 17 -1 (-50 1600)(-50 1400);
WIRE 17 -1 (-50 1600)(1050 1600);
FORCEPROP 2 LAST SIG_NAME P5E_CPU0_PE1_TX_C_DN<7:0>
J 0
(215 1610);
DISPLAY 0.680851 (215 1610);
PAINT WHITE (215 1610);
WIRE 17 -1 (-1425 3575)(-1425 3375);
WIRE 17 -1 (-2525 3575)(-1425 3575);
FORCEPROP 2 LAST SIG_NAME P5E_CPU0_PE1_TX_DN<15:8>
J 0
(-2510 3585);
DISPLAY 0.680851 (-2510 3585);
PAINT WHITE (-2510 3585);
WIRE 17 -1 (-1425 2375)(-1425 2175);
WIRE 17 -1 (-1425 2575)(-1425 2375);
WIRE 17 -1 (-1425 2775)(-1425 2575);
WIRE 17 -1 (-1425 2775)(-1425 2975);
WIRE 17 -1 (-1425 3175)(-1425 2975);
WIRE 17 -1 (-1425 3375)(-1425 3175);
WIRE 17 -1 (-1675 3325)(-1675 3525);
WIRE 17 -1 (-1675 3125)(-1675 3325);
WIRE 17 -1 (-2525 3525)(-1675 3525);
FORCEPROP 2 LAST SIG_NAME P5E_CPU0_PE1_TX_DP<15:8>
J 0
(-2510 3535);
DISPLAY 0.680851 (-2510 3535);
PAINT WHITE (-2510 3535);
WIRE 17 -1 (-1675 2125)(-1675 2325);
WIRE 17 -1 (-1675 2325)(-1675 2525);
WIRE 17 -1 (-1675 2525)(-1675 2725);
WIRE 17 -1 (-1675 2725)(-1675 2925);
WIRE 17 -1 (-1675 2925)(-1675 3125);
WIRE 17 -1 (-50 2575)(-50 2375);
WIRE 17 -1 (-50 2775)(-50 2575);
WIRE 17 -1 (-50 2375)(-50 2175);
WIRE 17 -1 (-50 2775)(-50 2975);
WIRE 17 -1 (-50 3175)(-50 2975);
WIRE 17 -1 (-50 3375)(-50 3175);
WIRE 17 -1 (-50 3575)(-50 3375);
WIRE 17 -1 (-50 3575)(1050 3575);
FORCEPROP 2 LAST SIG_NAME P5E_CPU0_PE1_TX_C_DN<15:8>
J 0
(215 3585);
DISPLAY 0.680851 (215 3585);
PAINT WHITE (215 3585);
WIRE 17 -1 (150 2525)(150 2325);
WIRE 17 -1 (150 2725)(150 2525);
WIRE 17 -1 (150 2325)(150 2125);
WIRE 17 -1 (150 2725)(150 2925);
WIRE 17 -1 (150 3125)(150 2925);
WIRE 17 -1 (150 3325)(150 3125);
WIRE 17 -1 (150 3525)(150 3325);
WIRE 17 -1 (150 3525)(1050 3525);
FORCEPROP 2 LAST SIG_NAME P5E_CPU0_PE1_TX_C_DP<15:8>
J 0
(215 3535);
DISPLAY 0.680851 (215 3535);
PAINT WHITE (215 3535);
WIRE 17 -1 (150 750)(150 550);
WIRE 17 -1 (150 750)(150 950);
WIRE 17 -1 (150 550)(150 350);
WIRE 17 -1 (150 350)(150 150);
WIRE 17 -1 (150 1150)(150 950);
WIRE 17 -1 (150 1350)(150 1150);
WIRE 17 -1 (150 1550)(150 1350);
WIRE 17 -1 (150 1550)(1050 1550);
FORCEPROP 2 LAST SIG_NAME P5E_CPU0_PE1_TX_C_DP<7:0>
J 0
(215 1560);
DISPLAY 0.680851 (215 1560);
PAINT WHITE (215 1560);
WIRE 17 -1 (2800 150)(2800 350);
WIRE 17 -1 (2800 350)(2800 550);
WIRE 17 -1 (2800 550)(2800 750);
WIRE 17 -1 (2800 750)(2800 950);
WIRE 17 -1 (2800 950)(2800 1150);
WIRE 17 -1 (2800 1150)(2800 1350);
WIRE 17 -1 (2800 1350)(2800 1550);
WIRE 17 -1 (1950 1550)(2800 1550);
FORCEPROP 2 LAST SIG_NAME P5E_CPU0_PE3_TX_DP<7:0>
J 0
(1990 1560);
DISPLAY 0.680851 (1990 1560);
PAINT WHITE (1990 1560);
WIRE 17 -1 (3050 600)(3050 400);
WIRE 17 -1 (3050 800)(3050 600);
WIRE 17 -1 (3050 400)(3050 200);
WIRE 17 -1 (3050 800)(3050 1000);
WIRE 17 -1 (3050 1200)(3050 1000);
WIRE 17 -1 (3050 1400)(3050 1200);
WIRE 17 -1 (3050 1600)(3050 1400);
WIRE 17 -1 (1950 1600)(3050 1600);
FORCEPROP 2 LAST SIG_NAME P5E_CPU0_PE3_TX_DN<7:0>
J 0
(1990 1610);
DISPLAY 0.680851 (1990 1610);
PAINT WHITE (1990 1610);
WIRE 17 -1 (2800 2725)(2800 2925);
WIRE 17 -1 (2800 2525)(2800 2725);
WIRE 17 -1 (2800 2925)(2800 3125);
WIRE 17 -1 (2800 3125)(2800 3325);
WIRE 17 -1 (2800 2325)(2800 2525);
WIRE 17 -1 (2800 2125)(2800 2325);
WIRE 17 -1 (2800 3325)(2800 3525);
WIRE 17 -1 (1950 3525)(2800 3525);
FORCEPROP 2 LAST SIG_NAME P5E_CPU0_PE3_TX_DP<15:8>
J 0
(1990 3535);
DISPLAY 0.680851 (1990 3535);
PAINT WHITE (1990 3535);
WIRE 17 -1 (3050 2775)(3050 2975);
WIRE 17 -1 (3050 2775)(3050 2575);
WIRE 17 -1 (3050 3175)(3050 2975);
WIRE 17 -1 (3050 3375)(3050 3175);
WIRE 17 -1 (3050 2575)(3050 2375);
WIRE 17 -1 (3050 2375)(3050 2175);
WIRE 17 -1 (3050 3575)(3050 3375);
WIRE 17 -1 (1950 3575)(3050 3575);
FORCEPROP 2 LAST SIG_NAME P5E_CPU0_PE3_TX_DN<15:8>
J 0
(1990 3585);
DISPLAY 0.680851 (1990 3585);
PAINT WHITE (1990 3585);
WIRE 17 -1 (4625 2725)(4625 2925);
WIRE 17 -1 (4625 2725)(4625 2525);
WIRE 17 -1 (4625 3125)(4625 2925);
WIRE 17 -1 (4625 3325)(4625 3125);
WIRE 17 -1 (4625 2525)(4625 2325);
WIRE 17 -1 (4625 2325)(4625 2125);
WIRE 17 -1 (4625 3525)(4625 3325);
WIRE 17 -1 (4625 3525)(5525 3525);
FORCEPROP 2 LAST SIG_NAME P5E_CPU0_PE3_TX_C_DP<15:8>
J 0
(4665 3535);
DISPLAY 0.680851 (4665 3535);
PAINT WHITE (4665 3535);
WIRE 17 -1 (4425 3375)(4425 3175);
WIRE 17 -1 (4425 3575)(4425 3375);
WIRE 17 -1 (4425 3175)(4425 2975);
WIRE 17 -1 (4425 2775)(4425 2975);
WIRE 17 -1 (4425 3575)(5525 3575);
FORCEPROP 2 LAST SIG_NAME P5E_CPU0_PE3_TX_C_DN<15:8>
J 0
(4665 3585);
DISPLAY 0.680851 (4665 3585);
PAINT WHITE (4665 3585);
WIRE 17 -1 (4625 1350)(4625 1150);
WIRE 17 -1 (4625 1550)(4625 1350);
WIRE 17 -1 (4625 1150)(4625 950);
WIRE 17 -1 (4625 750)(4625 950);
WIRE 17 -1 (4625 1550)(5525 1550);
FORCEPROP 2 LAST SIG_NAME P5E_CPU0_PE3_TX_C_DP<7:0>
J 0
(4665 1560);
DISPLAY 0.680851 (4665 1560);
PAINT WHITE (4665 1560);
WIRE 17 -1 (4425 600)(4425 400);
WIRE 17 -1 (4425 800)(4425 600);
WIRE 17 -1 (4425 400)(4425 200);
WIRE 17 -1 (4425 800)(4425 1000);
WIRE 17 -1 (4425 1200)(4425 1000);
WIRE 17 -1 (4425 1400)(4425 1200);
WIRE 17 -1 (4425 1600)(4425 1400);
WIRE 17 -1 (4425 1600)(5525 1600);
FORCEPROP 2 LAST SIG_NAME P5E_CPU0_PE3_TX_C_DN<7:0>
J 0
(4665 1610);
DISPLAY 0.680851 (4665 1610);
PAINT WHITE (4665 1610);
WIRE 17 -1 (4625 750)(4625 550);
WIRE 17 -1 (4625 550)(4625 350);
WIRE 17 -1 (4625 350)(4625 150);
WIRE 17 -1 (4425 2575)(4425 2375);
WIRE 17 -1 (4425 2775)(4425 2575);
WIRE 17 -1 (4425 2375)(4425 2175);
WIRE 16 -1 (-575 3550)(-150 3550);
WIRE 16 -1 (-575 3500)(50 3500);
WIRE 16 -1 (-575 3350)(-150 3350);
WIRE 16 -1 (-575 3300)(50 3300);
WIRE 16 -1 (-575 3150)(-150 3150);
WIRE 16 -1 (-575 3100)(50 3100);
WIRE 16 -1 (-725 2950)(-1325 2950);
WIRE 16 -1 (-725 2900)(-1575 2900);
WIRE 16 -1 (-575 125)(50 125);
WIRE 16 -1 (-575 1325)(50 1325);
WIRE 16 -1 (-575 1175)(-150 1175);
WIRE 16 -1 (3750 925)(2900 925);
WIRE 16 -1 (3750 775)(3150 775);
WIRE 16 -1 (3750 575)(3150 575);
WIRE 16 -1 (3900 325)(4525 325);
WIRE 16 -1 (3900 125)(4525 125);
WIRE 16 -1 (3900 175)(4325 175);
WIRE 16 -1 (3900 3300)(4525 3300);
WIRE 16 -1 (3900 3500)(4525 3500);
WIRE 16 -1 (3900 3550)(4325 3550);
WIRE 16 -1 (3900 3350)(4325 3350);
WIRE 16 -1 (3900 2700)(4525 2700);
WIRE 16 -1 (3900 2500)(4525 2500);
WIRE 16 -1 (3900 2300)(4525 2300);
WIRE 16 -1 (3900 2950)(4325 2950);
WIRE 16 -1 (3900 2750)(4325 2750);
WIRE 16 -1 (3900 2550)(4325 2550);
WIRE 16 -1 (3900 2150)(4325 2150);
WIRE 16 -1 (3900 2350)(4325 2350);
WIRE 16 -1 (3900 1525)(4525 1525);
WIRE 16 -1 (3900 1575)(4325 1575);
WIRE 16 -1 (3900 1375)(4325 1375);
WIRE 16 -1 (3900 1175)(4325 1175);
WIRE 16 -1 (3900 975)(4325 975);
WIRE 16 -1 (3900 725)(4525 725);
WIRE 16 -1 (3900 525)(4525 525);
WIRE 16 -1 (3900 925)(4525 925);
WIRE 16 -1 (3900 775)(4325 775);
WIRE 16 -1 (3900 575)(4325 575);
WIRE 16 -1 (3900 375)(4325 375);
WIRE 16 -1 (3900 2100)(4525 2100);
WIRE 16 -1 (3900 1325)(4525 1325);
WIRE 16 -1 (3900 1125)(4525 1125);
WIRE 16 -1 (3900 3150)(4325 3150);
WIRE 16 -1 (3900 3100)(4525 3100);
WIRE 16 -1 (3900 2900)(4525 2900);
WIRE 16 -1 (3750 3350)(3150 3350);
WIRE 16 -1 (3750 3150)(3150 3150);
WIRE 16 -1 (3750 3550)(3150 3550);
WIRE 16 -1 (3750 2150)(3150 2150);
WIRE 16 -1 (3750 2750)(3150 2750);
WIRE 16 -1 (3750 2350)(3150 2350);
WIRE 16 -1 (3750 2550)(3150 2550);
WIRE 16 -1 (3750 2950)(3150 2950);
WIRE 16 -1 (3750 3300)(2900 3300);
WIRE 16 -1 (3750 3500)(2900 3500);
WIRE 16 -1 (3750 3100)(2900 3100);
WIRE 16 -1 (3750 2100)(2900 2100);
WIRE 16 -1 (3750 2700)(2900 2700);
WIRE 16 -1 (3750 2500)(2900 2500);
WIRE 16 -1 (3750 2300)(2900 2300);
WIRE 16 -1 (3750 2900)(2900 2900);
WIRE 16 -1 (3750 1575)(3150 1575);
WIRE 16 -1 (3750 1375)(3150 1375);
WIRE 16 -1 (3750 1175)(3150 1175);
WIRE 16 -1 (3750 975)(3150 975);
WIRE 16 -1 (3750 175)(3150 175);
WIRE 16 -1 (3750 375)(3150 375);
WIRE 16 -1 (3750 1525)(2900 1525);
WIRE 16 -1 (3750 1325)(2900 1325);
WIRE 16 -1 (3750 525)(2900 525);
WIRE 16 -1 (3750 325)(2900 325);
WIRE 16 -1 (3750 725)(2900 725);
WIRE 16 -1 (3750 1125)(2900 1125);
WIRE 16 -1 (3750 125)(2900 125);
WIRE 16 -1 (-575 1125)(50 1125);
WIRE 16 -1 (-575 1525)(50 1525);
WIRE 16 -1 (-575 325)(50 325);
WIRE 16 -1 (-575 925)(50 925);
WIRE 16 -1 (-575 725)(50 725);
WIRE 16 -1 (-575 525)(50 525);
WIRE 16 -1 (-575 2100)(50 2100);
WIRE 16 -1 (-575 2900)(50 2900);
WIRE 16 -1 (-575 2700)(50 2700);
WIRE 16 -1 (-575 2500)(50 2500);
WIRE 16 -1 (-575 2300)(50 2300);
WIRE 16 -1 (-575 2950)(-150 2950);
WIRE 16 -1 (-575 2750)(-150 2750);
WIRE 16 -1 (-575 2550)(-150 2550);
WIRE 16 -1 (-575 2150)(-150 2150);
WIRE 16 -1 (-575 2350)(-150 2350);
WIRE 16 -1 (-725 3100)(-1575 3100);
WIRE 16 -1 (-725 2750)(-1325 2750);
WIRE 16 -1 (-725 2700)(-1575 2700);
WIRE 16 -1 (-725 2500)(-1575 2500);
WIRE 16 -1 (-725 2300)(-1575 2300);
WIRE 16 -1 (-725 2100)(-1575 2100);
WIRE 16 -1 (-725 3300)(-1575 3300);
WIRE 16 -1 (-725 3350)(-1325 3350);
WIRE 16 -1 (-725 3500)(-1575 3500);
WIRE 16 -1 (-725 3150)(-1325 3150);
WIRE 16 -1 (-725 2350)(-1325 2350);
WIRE 16 -1 (-725 2550)(-1325 2550);
WIRE 16 -1 (-725 2150)(-1325 2150);
WIRE 16 -1 (-725 3550)(-1325 3550);
WIRE 16 -1 (-575 1575)(-150 1575);
WIRE 16 -1 (-575 1375)(-150 1375);
WIRE 16 -1 (-575 575)(-150 575);
WIRE 16 -1 (-575 975)(-150 975);
WIRE 16 -1 (-575 775)(-150 775);
WIRE 16 -1 (-575 375)(-150 375);
WIRE 16 -1 (-575 175)(-150 175);
WIRE 16 -1 (-725 375)(-1325 375);
WIRE 16 -1 (-725 725)(-1575 725);
WIRE 16 -1 (-725 925)(-1575 925);
WIRE 16 -1 (-725 1575)(-1325 1575);
WIRE 16 -1 (-725 1175)(-1325 1175);
WIRE 16 -1 (-725 1325)(-1575 1325);
WIRE 16 -1 (-725 775)(-1325 775);
WIRE 16 -1 (-725 175)(-1325 175);
WIRE 16 -1 (-725 1525)(-1575 1525);
WIRE 16 -1 (-725 1375)(-1325 1375);
WIRE 16 -1 (-725 125)(-1575 125);
WIRE 16 -1 (-725 325)(-1575 325);
WIRE 16 -1 (-725 525)(-1575 525);
WIRE 16 -1 (-725 575)(-1325 575);
WIRE 16 -1 (-725 975)(-1325 975);
WIRE 16 -1 (-725 1125)(-1575 1125);
FORCENOTE
CPU0 PCIE1 TX
(-2050 -500) 0;
DISPLAY LEFT (-2050 -500);
DISPLAY 4.148936 (-2050 -500);
PAINT WHITE (-2050 -500);
FORCENOTE
CPU0 PCIE3 TX
(2550 -500) 0;
DISPLAY LEFT (2550 -500);
DISPLAY 4.148936 (2550 -500);
PAINT WHITE (2550 -500);
FORCENOTE
20210527 MODIFY FOR GT
(-2100 4100) 0;
DISPLAY LEFT (-2100 4100);
DISPLAY 2.510638 (-2100 4100);
PAINT PINK (-2100 4100);
QUIT
